(kicad_sch
	(version 20231120)
	(generator "eeschema")
	(generator_version "8.0")
	(paper "A3")
	(title_block
		(title "GSML Serializer ")
		(date "2024-11-27")
		(rev "1.1.1")
		(company "Antmicro Ltd")
		(comment 1 "www.antmicro.com")
	)
	(junction
		(at 330.2 201.93)
		(diameter 0)
		(color 0 0 0 0)
	)
	(junction
		(at 273.05 207.01)
		(diameter 0)
		(color 0 0 0 0)
	)
	(junction
		(at 312.42 201.93)
		(diameter 0)
		(color 0 0 0 0)
	)
	(junction
		(at 351.79 138.43)
		(diameter 0)
		(color 0 0 0 0)
	)
	(junction
		(at 321.31 201.93)
		(diameter 0)
		(color 0 0 0 0)
	)
	(junction
		(at 144.78 81.28)
		(diameter 0)
		(color 0 0 0 0)
	)
	(junction
		(at 157.48 204.47)
		(diameter 0)
		(color 0 0 0 0)
	)
	(junction
		(at 270.51 127)
		(diameter 0)
		(color 0 0 0 0)
	)
	(junction
		(at 339.09 201.93)
		(diameter 0)
		(color 0 0 0 0)
	)
	(junction
		(at 55.88 204.47)
		(diameter 0)
		(color 0 0 0 0)
	)
	(junction
		(at 118.11 204.47)
		(diameter 0)
		(color 0 0 0 0)
	)
	(junction
		(at 71.12 209.55)
		(diameter 0)
		(color 0 0 0 0)
	)
	(junction
		(at 76.2 81.28)
		(diameter 0)
		(color 0 0 0 0)
	)
	(junction
		(at 161.29 81.28)
		(diameter 0)
		(color 0 0 0 0)
	)
	(junction
		(at 339.09 130.81)
		(diameter 0)
		(color 0 0 0 0)
	)
	(junction
		(at 278.13 127)
		(diameter 0)
		(color 0 0 0 0)
	)
	(junction
		(at 87.63 86.36)
		(diameter 0)
		(color 0 0 0 0)
	)
	(junction
		(at 285.75 54.61)
		(diameter 0)
		(color 0 0 0 0)
	)
	(junction
		(at 135.89 91.44)
		(diameter 0)
		(color 0 0 0 0)
	)
	(junction
		(at 118.11 214.63)
		(diameter 0)
		(color 0 0 0 0)
	)
	(junction
		(at 158.75 227.33)
		(diameter 0)
		(color 0 0 0 0)
	)
	(junction
		(at 261.62 212.09)
		(diameter 0)
		(color 0 0 0 0)
	)
	(junction
		(at 127 81.28)
		(diameter 0)
		(color 0 0 0 0)
	)
	(junction
		(at 127 204.47)
		(diameter 0)
		(color 0 0 0 0)
	)
	(junction
		(at 350.52 201.93)
		(diameter 0)
		(color 0 0 0 0)
	)
	(junction
		(at 153.67 81.28)
		(diameter 0)
		(color 0 0 0 0)
	)
	(junction
		(at 135.89 204.47)
		(diameter 0)
		(color 0 0 0 0)
	)
	(junction
		(at 317.5 54.61)
		(diameter 0)
		(color 0 0 0 0)
	)
	(junction
		(at 346.71 201.93)
		(diameter 0)
		(color 0 0 0 0)
	)
	(junction
		(at 321.31 212.09)
		(diameter 0)
		(color 0 0 0 0)
	)
	(junction
		(at 148.59 204.47)
		(diameter 0)
		(color 0 0 0 0)
	)
	(junction
		(at 135.89 81.28)
		(diameter 0)
		(color 0 0 0 0)
	)
	(junction
		(at 165.1 81.28)
		(diameter 0)
		(color 0 0 0 0)
	)
	(junction
		(at 261.62 201.93)
		(diameter 0)
		(color 0 0 0 0)
	)
	(junction
		(at 304.8 127)
		(diameter 0)
		(color 0 0 0 0)
	)
	(junction
		(at 311.15 127)
		(diameter 0)
		(color 0 0 0 0)
	)
	(junction
		(at 54.61 81.28)
		(diameter 0)
		(color 0 0 0 0)
	)
	(junction
		(at 110.49 204.47)
		(diameter 0)
		(color 0 0 0 0)
	)
	(junction
		(at 171.45 234.95)
		(diameter 0)
		(color 0 0 0 0)
	)
	(junction
		(at 76.2 91.44)
		(diameter 0)
		(color 0 0 0 0)
	)
	(wire
		(pts
			(xy 127 204.47) (xy 118.11 204.47)
		)
		(stroke
			(width 0)
			(type default)
		)
	)
	(wire
		(pts
			(xy 144.78 81.28) (xy 135.89 81.28)
		)
		(stroke
			(width 0)
			(type default)
		)
	)
	(wire
		(pts
			(xy 312.42 207.01) (xy 312.42 201.93)
		)
		(stroke
			(width 0)
			(type default)
		)
	)
	(wire
		(pts
			(xy 311.15 54.61) (xy 317.5 54.61)
		)
		(stroke
			(width 0)
			(type default)
		)
	)
	(wire
		(pts
			(xy 300.99 129.54) (xy 300.99 135.89)
		)
		(stroke
			(width 0)
			(type default)
		)
	)
	(wire
		(pts
			(xy 76.2 85.09) (xy 76.2 81.28)
		)
		(stroke
			(width 0)
			(type default)
		)
	)
	(wire
		(pts
			(xy 116.84 81.28) (xy 127 81.28)
		)
		(stroke
			(width 0)
			(type default)
		)
	)
	(wire
		(pts
			(xy 270.51 127) (xy 270.51 129.54)
		)
		(stroke
			(width 0)
			(type default)
		)
	)
	(wire
		(pts
			(xy 194.31 86.36) (xy 194.31 85.09)
		)
		(stroke
			(width 0)
			(type default)
		)
	)
	(wire
		(pts
			(xy 54.61 78.74) (xy 54.61 81.28)
		)
		(stroke
			(width 0)
			(type default)
		)
	)
	(wire
		(pts
			(xy 127 217.17) (xy 127 204.47)
		)
		(stroke
			(width 0)
			(type default)
		)
	)
	(wire
		(pts
			(xy 317.5 54.61) (xy 323.85 54.61)
		)
		(stroke
			(width 0)
			(type default)
		)
	)
	(wire
		(pts
			(xy 161.29 72.39) (xy 161.29 81.28)
		)
		(stroke
			(width 0)
			(type default)
		)
	)
	(wire
		(pts
			(xy 261.62 212.09) (xy 261.62 213.36)
		)
		(stroke
			(width 0)
			(type default)
		)
	)
	(wire
		(pts
			(xy 302.26 212.09) (xy 321.31 212.09)
		)
		(stroke
			(width 0)
			(type default)
		)
	)
	(wire
		(pts
			(xy 171.45 209.55) (xy 171.45 212.09)
		)
		(stroke
			(width 0)
			(type default)
		)
	)
	(wire
		(pts
			(xy 158.75 228.6) (xy 158.75 227.33)
		)
		(stroke
			(width 0)
			(type default)
		)
	)
	(wire
		(pts
			(xy 157.48 203.2) (xy 157.48 204.47)
		)
		(stroke
			(width 0)
			(type default)
		)
	)
	(wire
		(pts
			(xy 118.11 222.25) (xy 118.11 223.52)
		)
		(stroke
			(width 0)
			(type default)
		)
	)
	(wire
		(pts
			(xy 171.45 236.22) (xy 171.45 234.95)
		)
		(stroke
			(width 0)
			(type default)
		)
	)
	(wire
		(pts
			(xy 127 86.36) (xy 127 81.28)
		)
		(stroke
			(width 0)
			(type default)
		)
	)
	(wire
		(pts
			(xy 153.67 92.71) (xy 153.67 81.28)
		)
		(stroke
			(width 0)
			(type default)
		)
	)
	(wire
		(pts
			(xy 116.84 91.44) (xy 135.89 91.44)
		)
		(stroke
			(width 0)
			(type default)
		)
	)
	(wire
		(pts
			(xy 77.47 217.17) (xy 77.47 214.63)
		)
		(stroke
			(width 0)
			(type default)
		)
	)
	(wire
		(pts
			(xy 142.24 204.47) (xy 148.59 204.47)
		)
		(stroke
			(width 0)
			(type default)
		)
	)
	(wire
		(pts
			(xy 153.67 81.28) (xy 154.94 81.28)
		)
		(stroke
			(width 0)
			(type default)
		)
	)
	(wire
		(pts
			(xy 76.2 81.28) (xy 96.52 81.28)
		)
		(stroke
			(width 0)
			(type default)
		)
	)
	(wire
		(pts
			(xy 106.68 209.55) (xy 110.49 209.55)
		)
		(stroke
			(width 0)
			(type default)
		)
	)
	(wire
		(pts
			(xy 76.2 90.17) (xy 76.2 91.44)
		)
		(stroke
			(width 0)
			(type default)
		)
	)
	(wire
		(pts
			(xy 135.89 81.28) (xy 135.89 82.55)
		)
		(stroke
			(width 0)
			(type default)
		)
	)
	(wire
		(pts
			(xy 339.09 201.93) (xy 340.36 201.93)
		)
		(stroke
			(width 0)
			(type default)
		)
	)
	(polyline
		(pts
			(xy 220.98 81.28) (xy 406.4 81.28)
		)
		(stroke
			(width 0)
			(type dash)
		)
	)
	(wire
		(pts
			(xy 321.31 201.93) (xy 321.31 203.2)
		)
		(stroke
			(width 0)
			(type default)
		)
	)
	(wire
		(pts
			(xy 270.51 127) (xy 278.13 127)
		)
		(stroke
			(width 0)
			(type default)
		)
	)
	(wire
		(pts
			(xy 161.29 81.28) (xy 165.1 81.28)
		)
		(stroke
			(width 0)
			(type default)
		)
	)
	(wire
		(pts
			(xy 118.11 214.63) (xy 118.11 217.17)
		)
		(stroke
			(width 0)
			(type default)
		)
	)
	(wire
		(pts
			(xy 317.5 53.34) (xy 317.5 54.61)
		)
		(stroke
			(width 0)
			(type default)
		)
	)
	(wire
		(pts
			(xy 171.45 229.87) (xy 171.45 234.95)
		)
		(stroke
			(width 0)
			(type default)
		)
	)
	(wire
		(pts
			(xy 350.52 193.04) (xy 350.52 201.93)
		)
		(stroke
			(width 0)
			(type default)
		)
	)
	(wire
		(pts
			(xy 321.31 212.09) (xy 321.31 213.36)
		)
		(stroke
			(width 0)
			(type default)
		)
	)
	(wire
		(pts
			(xy 346.71 201.93) (xy 350.52 201.93)
		)
		(stroke
			(width 0)
			(type default)
		)
	)
	(wire
		(pts
			(xy 160.02 81.28) (xy 161.29 81.28)
		)
		(stroke
			(width 0)
			(type default)
		)
	)
	(wire
		(pts
			(xy 257.81 213.36) (xy 257.81 212.09)
		)
		(stroke
			(width 0)
			(type default)
		)
	)
	(wire
		(pts
			(xy 158.75 234.95) (xy 171.45 234.95)
		)
		(stroke
			(width 0)
			(type default)
		)
	)
	(wire
		(pts
			(xy 339.09 218.44) (xy 339.09 219.71)
		)
		(stroke
			(width 0)
			(type default)
		)
	)
	(wire
		(pts
			(xy 339.09 130.81) (xy 345.44 130.81)
		)
		(stroke
			(width 0)
			(type default)
		)
	)
	(wire
		(pts
			(xy 261.62 205.74) (xy 261.62 201.93)
		)
		(stroke
			(width 0)
			(type default)
		)
	)
	(wire
		(pts
			(xy 302.26 207.01) (xy 303.53 207.01)
		)
		(stroke
			(width 0)
			(type default)
		)
	)
	(wire
		(pts
			(xy 285.75 54.61) (xy 293.37 54.61)
		)
		(stroke
			(width 0)
			(type default)
		)
	)
	(wire
		(pts
			(xy 257.81 212.09) (xy 261.62 212.09)
		)
		(stroke
			(width 0)
			(type default)
		)
	)
	(wire
		(pts
			(xy 135.89 91.44) (xy 135.89 92.71)
		)
		(stroke
			(width 0)
			(type default)
		)
	)
	(wire
		(pts
			(xy 71.12 209.55) (xy 71.12 210.82)
		)
		(stroke
			(width 0)
			(type default)
		)
	)
	(wire
		(pts
			(xy 118.11 210.82) (xy 118.11 214.63)
		)
		(stroke
			(width 0)
			(type default)
		)
	)
	(wire
		(pts
			(xy 95.25 91.44) (xy 96.52 91.44)
		)
		(stroke
			(width 0)
			(type default)
		)
	)
	(wire
		(pts
			(xy 54.61 93.98) (xy 54.61 95.25)
		)
		(stroke
			(width 0)
			(type default)
		)
	)
	(wire
		(pts
			(xy 273.05 193.04) (xy 273.05 194.31)
		)
		(stroke
			(width 0)
			(type default)
		)
	)
	(wire
		(pts
			(xy 350.52 201.93) (xy 350.52 207.01)
		)
		(stroke
			(width 0)
			(type default)
		)
	)
	(wire
		(pts
			(xy 165.1 72.39) (xy 165.1 81.28)
		)
		(stroke
			(width 0)
			(type default)
		)
	)
	(wire
		(pts
			(xy 273.05 213.36) (xy 273.05 214.63)
		)
		(stroke
			(width 0)
			(type default)
		)
	)
	(wire
		(pts
			(xy 87.63 92.71) (xy 87.63 93.98)
		)
		(stroke
			(width 0)
			(type default)
		)
	)
	(wire
		(pts
			(xy 76.2 80.01) (xy 76.2 81.28)
		)
		(stroke
			(width 0)
			(type default)
		)
	)
	(wire
		(pts
			(xy 254 199.39) (xy 254 201.93)
		)
		(stroke
			(width 0)
			(type default)
		)
	)
	(wire
		(pts
			(xy 71.12 200.66) (xy 71.12 209.55)
		)
		(stroke
			(width 0)
			(type default)
		)
	)
	(wire
		(pts
			(xy 304.8 125.73) (xy 304.8 127)
		)
		(stroke
			(width 0)
			(type default)
		)
	)
	(wire
		(pts
			(xy 350.52 218.44) (xy 350.52 219.71)
		)
		(stroke
			(width 0)
			(type default)
		)
	)
	(wire
		(pts
			(xy 71.12 209.55) (xy 78.74 209.55)
		)
		(stroke
			(width 0)
			(type default)
		)
	)
	(wire
		(pts
			(xy 135.89 217.17) (xy 135.89 204.47)
		)
		(stroke
			(width 0)
			(type default)
		)
	)
	(wire
		(pts
			(xy 135.89 204.47) (xy 137.16 204.47)
		)
		(stroke
			(width 0)
			(type default)
		)
	)
	(wire
		(pts
			(xy 77.47 214.63) (xy 78.74 214.63)
		)
		(stroke
			(width 0)
			(type default)
		)
	)
	(wire
		(pts
			(xy 118.11 204.47) (xy 118.11 205.74)
		)
		(stroke
			(width 0)
			(type default)
		)
	)
	(wire
		(pts
			(xy 270.51 124.46) (xy 270.51 127)
		)
		(stroke
			(width 0)
			(type default)
		)
	)
	(wire
		(pts
			(xy 158.75 233.68) (xy 158.75 234.95)
		)
		(stroke
			(width 0)
			(type default)
		)
	)
	(wire
		(pts
			(xy 54.61 81.28) (xy 54.61 82.55)
		)
		(stroke
			(width 0)
			(type default)
		)
	)
	(wire
		(pts
			(xy 165.1 81.28) (xy 167.64 81.28)
		)
		(stroke
			(width 0)
			(type default)
		)
	)
	(wire
		(pts
			(xy 318.77 201.93) (xy 321.31 201.93)
		)
		(stroke
			(width 0)
			(type default)
		)
	)
	(wire
		(pts
			(xy 95.25 92.71) (xy 95.25 91.44)
		)
		(stroke
			(width 0)
			(type default)
		)
	)
	(wire
		(pts
			(xy 273.05 199.39) (xy 273.05 207.01)
		)
		(stroke
			(width 0)
			(type default)
		)
	)
	(wire
		(pts
			(xy 158.75 226.06) (xy 158.75 227.33)
		)
		(stroke
			(width 0)
			(type default)
		)
	)
	(wire
		(pts
			(xy 330.2 218.44) (xy 330.2 219.71)
		)
		(stroke
			(width 0)
			(type default)
		)
	)
	(wire
		(pts
			(xy 278.13 127) (xy 279.4 127)
		)
		(stroke
			(width 0)
			(type default)
		)
	)
	(wire
		(pts
			(xy 72.39 92.71) (xy 72.39 91.44)
		)
		(stroke
			(width 0)
			(type default)
		)
	)
	(wire
		(pts
			(xy 330.2 201.93) (xy 321.31 201.93)
		)
		(stroke
			(width 0)
			(type default)
		)
	)
	(wire
		(pts
			(xy 351.79 113.03) (xy 351.79 115.57)
		)
		(stroke
			(width 0)
			(type default)
		)
	)
	(wire
		(pts
			(xy 311.15 134.62) (xy 311.15 135.89)
		)
		(stroke
			(width 0)
			(type default)
		)
	)
	(wire
		(pts
			(xy 330.2 201.93) (xy 339.09 201.93)
		)
		(stroke
			(width 0)
			(type default)
		)
	)
	(wire
		(pts
			(xy 285.75 52.07) (xy 285.75 54.61)
		)
		(stroke
			(width 0)
			(type default)
		)
	)
	(wire
		(pts
			(xy 55.88 204.47) (xy 78.74 204.47)
		)
		(stroke
			(width 0)
			(type default)
		)
	)
	(wire
		(pts
			(xy 351.79 133.35) (xy 351.79 138.43)
		)
		(stroke
			(width 0)
			(type default)
		)
	)
	(polyline
		(pts
			(xy 12.7 140.97) (xy 220.98 140.97)
		)
		(stroke
			(width 0)
			(type dash)
		)
	)
	(wire
		(pts
			(xy 116.84 86.36) (xy 118.11 86.36)
		)
		(stroke
			(width 0)
			(type default)
		)
	)
	(wire
		(pts
			(xy 87.63 86.36) (xy 96.52 86.36)
		)
		(stroke
			(width 0)
			(type default)
		)
	)
	(wire
		(pts
			(xy 285.75 54.61) (xy 285.75 55.88)
		)
		(stroke
			(width 0)
			(type default)
		)
	)
	(wire
		(pts
			(xy 148.59 204.47) (xy 157.48 204.47)
		)
		(stroke
			(width 0)
			(type default)
		)
	)
	(wire
		(pts
			(xy 165.1 81.28) (xy 165.1 86.36)
		)
		(stroke
			(width 0)
			(type default)
		)
	)
	(wire
		(pts
			(xy 254 201.93) (xy 261.62 201.93)
		)
		(stroke
			(width 0)
			(type default)
		)
	)
	(wire
		(pts
			(xy 135.89 87.63) (xy 135.89 91.44)
		)
		(stroke
			(width 0)
			(type default)
		)
	)
	(wire
		(pts
			(xy 285.75 62.23) (xy 285.75 60.96)
		)
		(stroke
			(width 0)
			(type default)
		)
	)
	(wire
		(pts
			(xy 292.1 58.42) (xy 292.1 62.23)
		)
		(stroke
			(width 0)
			(type default)
		)
	)
	(wire
		(pts
			(xy 72.39 91.44) (xy 76.2 91.44)
		)
		(stroke
			(width 0)
			(type default)
		)
	)
	(wire
		(pts
			(xy 165.1 97.79) (xy 165.1 99.06)
		)
		(stroke
			(width 0)
			(type default)
		)
	)
	(wire
		(pts
			(xy 293.37 58.42) (xy 292.1 58.42)
		)
		(stroke
			(width 0)
			(type default)
		)
	)
	(wire
		(pts
			(xy 280.67 213.36) (xy 280.67 212.09)
		)
		(stroke
			(width 0)
			(type default)
		)
	)
	(wire
		(pts
			(xy 279.4 129.54) (xy 278.13 129.54)
		)
		(stroke
			(width 0)
			(type default)
		)
	)
	(wire
		(pts
			(xy 127 204.47) (xy 135.89 204.47)
		)
		(stroke
			(width 0)
			(type default)
		)
	)
	(wire
		(pts
			(xy 157.48 204.47) (xy 158.75 204.47)
		)
		(stroke
			(width 0)
			(type default)
		)
	)
	(wire
		(pts
			(xy 171.45 217.17) (xy 171.45 219.71)
		)
		(stroke
			(width 0)
			(type default)
		)
	)
	(wire
		(pts
			(xy 127 81.28) (xy 128.27 81.28)
		)
		(stroke
			(width 0)
			(type default)
		)
	)
	(wire
		(pts
			(xy 171.45 203.2) (xy 171.45 204.47)
		)
		(stroke
			(width 0)
			(type default)
		)
	)
	(wire
		(pts
			(xy 330.2 213.36) (xy 330.2 201.93)
		)
		(stroke
			(width 0)
			(type default)
		)
	)
	(wire
		(pts
			(xy 339.09 138.43) (xy 351.79 138.43)
		)
		(stroke
			(width 0)
			(type default)
		)
	)
	(wire
		(pts
			(xy 321.31 218.44) (xy 321.31 219.71)
		)
		(stroke
			(width 0)
			(type default)
		)
	)
	(wire
		(pts
			(xy 350.52 201.93) (xy 353.06 201.93)
		)
		(stroke
			(width 0)
			(type default)
		)
	)
	(wire
		(pts
			(xy 54.61 81.28) (xy 76.2 81.28)
		)
		(stroke
			(width 0)
			(type default)
		)
	)
	(wire
		(pts
			(xy 351.79 106.68) (xy 351.79 107.95)
		)
		(stroke
			(width 0)
			(type default)
		)
	)
	(wire
		(pts
			(xy 351.79 120.65) (xy 351.79 123.19)
		)
		(stroke
			(width 0)
			(type default)
		)
	)
	(wire
		(pts
			(xy 311.15 127) (xy 304.8 127)
		)
		(stroke
			(width 0)
			(type default)
		)
	)
	(wire
		(pts
			(xy 350.52 212.09) (xy 350.52 213.36)
		)
		(stroke
			(width 0)
			(type default)
		)
	)
	(wire
		(pts
			(xy 261.62 210.82) (xy 261.62 212.09)
		)
		(stroke
			(width 0)
			(type default)
		)
	)
	(wire
		(pts
			(xy 127 222.25) (xy 127 223.52)
		)
		(stroke
			(width 0)
			(type default)
		)
	)
	(wire
		(pts
			(xy 55.88 209.55) (xy 55.88 204.47)
		)
		(stroke
			(width 0)
			(type default)
		)
	)
	(polyline
		(pts
			(xy 220.98 12.7) (xy 220.98 284.48)
		)
		(stroke
			(width 0)
			(type dash)
		)
	)
	(wire
		(pts
			(xy 99.06 214.63) (xy 118.11 214.63)
		)
		(stroke
			(width 0)
			(type default)
		)
	)
	(wire
		(pts
			(xy 351.79 139.7) (xy 351.79 138.43)
		)
		(stroke
			(width 0)
			(type default)
		)
	)
	(wire
		(pts
			(xy 312.42 201.93) (xy 313.69 201.93)
		)
		(stroke
			(width 0)
			(type default)
		)
	)
	(wire
		(pts
			(xy 148.59 203.2) (xy 148.59 204.47)
		)
		(stroke
			(width 0)
			(type default)
		)
	)
	(wire
		(pts
			(xy 299.72 129.54) (xy 300.99 129.54)
		)
		(stroke
			(width 0)
			(type default)
		)
	)
	(wire
		(pts
			(xy 311.15 127) (xy 311.15 129.54)
		)
		(stroke
			(width 0)
			(type default)
		)
	)
	(wire
		(pts
			(xy 110.49 209.55) (xy 110.49 204.47)
		)
		(stroke
			(width 0)
			(type default)
		)
	)
	(wire
		(pts
			(xy 311.15 124.46) (xy 311.15 127)
		)
		(stroke
			(width 0)
			(type default)
		)
	)
	(wire
		(pts
			(xy 87.63 72.39) (xy 87.63 73.66)
		)
		(stroke
			(width 0)
			(type default)
		)
	)
	(wire
		(pts
			(xy 135.89 97.79) (xy 135.89 99.06)
		)
		(stroke
			(width 0)
			(type default)
		)
	)
	(polyline
		(pts
			(xy 220.98 167.64) (xy 407.67 167.64)
		)
		(stroke
			(width 0)
			(type dash)
		)
	)
	(wire
		(pts
			(xy 278.13 127) (xy 278.13 129.54)
		)
		(stroke
			(width 0)
			(type default)
		)
	)
	(wire
		(pts
			(xy 71.12 194.31) (xy 71.12 195.58)
		)
		(stroke
			(width 0)
			(type default)
		)
	)
	(wire
		(pts
			(xy 158.75 227.33) (xy 165.1 227.33)
		)
		(stroke
			(width 0)
			(type default)
		)
	)
	(wire
		(pts
			(xy 321.31 208.28) (xy 321.31 212.09)
		)
		(stroke
			(width 0)
			(type default)
		)
	)
	(wire
		(pts
			(xy 345.44 201.93) (xy 346.71 201.93)
		)
		(stroke
			(width 0)
			(type default)
		)
	)
	(wire
		(pts
			(xy 273.05 207.01) (xy 281.94 207.01)
		)
		(stroke
			(width 0)
			(type default)
		)
	)
	(wire
		(pts
			(xy 71.12 217.17) (xy 71.12 215.9)
		)
		(stroke
			(width 0)
			(type default)
		)
	)
	(wire
		(pts
			(xy 135.89 222.25) (xy 135.89 223.52)
		)
		(stroke
			(width 0)
			(type default)
		)
	)
	(wire
		(pts
			(xy 339.09 128.27) (xy 339.09 130.81)
		)
		(stroke
			(width 0)
			(type default)
		)
	)
	(wire
		(pts
			(xy 339.09 213.36) (xy 339.09 201.93)
		)
		(stroke
			(width 0)
			(type default)
		)
	)
	(wire
		(pts
			(xy 165.1 91.44) (xy 165.1 92.71)
		)
		(stroke
			(width 0)
			(type default)
		)
	)
	(wire
		(pts
			(xy 339.09 132.08) (xy 339.09 130.81)
		)
		(stroke
			(width 0)
			(type default)
		)
	)
	(wire
		(pts
			(xy 144.78 81.28) (xy 153.67 81.28)
		)
		(stroke
			(width 0)
			(type default)
		)
	)
	(wire
		(pts
			(xy 261.62 200.66) (xy 261.62 201.93)
		)
		(stroke
			(width 0)
			(type default)
		)
	)
	(wire
		(pts
			(xy 87.63 78.74) (xy 87.63 86.36)
		)
		(stroke
			(width 0)
			(type default)
		)
	)
	(wire
		(pts
			(xy 76.2 91.44) (xy 76.2 92.71)
		)
		(stroke
			(width 0)
			(type default)
		)
	)
	(wire
		(pts
			(xy 280.67 212.09) (xy 281.94 212.09)
		)
		(stroke
			(width 0)
			(type default)
		)
	)
	(wire
		(pts
			(xy 261.62 201.93) (xy 281.94 201.93)
		)
		(stroke
			(width 0)
			(type default)
		)
	)
	(wire
		(pts
			(xy 299.72 127) (xy 304.8 127)
		)
		(stroke
			(width 0)
			(type default)
		)
	)
	(wire
		(pts
			(xy 346.71 193.04) (xy 346.71 201.93)
		)
		(stroke
			(width 0)
			(type default)
		)
	)
	(wire
		(pts
			(xy 87.63 86.36) (xy 87.63 87.63)
		)
		(stroke
			(width 0)
			(type default)
		)
	)
	(wire
		(pts
			(xy 308.61 207.01) (xy 312.42 207.01)
		)
		(stroke
			(width 0)
			(type default)
		)
	)
	(wire
		(pts
			(xy 144.78 97.79) (xy 144.78 99.06)
		)
		(stroke
			(width 0)
			(type default)
		)
	)
	(wire
		(pts
			(xy 123.19 86.36) (xy 127 86.36)
		)
		(stroke
			(width 0)
			(type default)
		)
	)
	(wire
		(pts
			(xy 302.26 201.93) (xy 312.42 201.93)
		)
		(stroke
			(width 0)
			(type default)
		)
	)
	(wire
		(pts
			(xy 133.35 81.28) (xy 135.89 81.28)
		)
		(stroke
			(width 0)
			(type default)
		)
	)
	(wire
		(pts
			(xy 116.84 204.47) (xy 118.11 204.47)
		)
		(stroke
			(width 0)
			(type default)
		)
	)
	(wire
		(pts
			(xy 110.49 204.47) (xy 111.76 204.47)
		)
		(stroke
			(width 0)
			(type default)
		)
	)
	(wire
		(pts
			(xy 144.78 92.71) (xy 144.78 81.28)
		)
		(stroke
			(width 0)
			(type default)
		)
	)
	(wire
		(pts
			(xy 55.88 214.63) (xy 55.88 217.17)
		)
		(stroke
			(width 0)
			(type default)
		)
	)
	(wire
		(pts
			(xy 270.51 134.62) (xy 270.51 135.89)
		)
		(stroke
			(width 0)
			(type default)
		)
	)
	(wire
		(pts
			(xy 339.09 137.16) (xy 339.09 138.43)
		)
		(stroke
			(width 0)
			(type default)
		)
	)
	(wire
		(pts
			(xy 55.88 203.2) (xy 55.88 204.47)
		)
		(stroke
			(width 0)
			(type default)
		)
	)
	(wire
		(pts
			(xy 99.06 209.55) (xy 101.6 209.55)
		)
		(stroke
			(width 0)
			(type default)
		)
	)
	(wire
		(pts
			(xy 54.61 87.63) (xy 54.61 88.9)
		)
		(stroke
			(width 0)
			(type default)
		)
	)
	(wire
		(pts
			(xy 153.67 97.79) (xy 153.67 99.06)
		)
		(stroke
			(width 0)
			(type default)
		)
	)
	(wire
		(pts
			(xy 99.06 204.47) (xy 110.49 204.47)
		)
		(stroke
			(width 0)
			(type default)
		)
	)
	(wire
		(pts
			(xy 273.05 207.01) (xy 273.05 208.28)
		)
		(stroke
			(width 0)
			(type default)
		)
	)
	(text "1V8 BUCK CONVERTER"
		(exclude_from_sim no)
		(at 83.82 182.88 0)
		(effects
			(font
				(size 2.54 2.54)
				(thickness 0.508)
				(bold yes)
			)
			(justify left bottom)
		)
	)
	(text "1V8 to 1V2 LDO 300mA"
		(exclude_from_sim no)
		(at 266.7 106.68 0)
		(effects
			(font
				(size 2.54 2.54)
				(thickness 0.508)
				(bold yes)
			)
			(justify left bottom)
		)
	)
	(text "3V3 BUCK CONVERTER"
		(exclude_from_sim no)
		(at 276.86 182.88 0)
		(effects
			(font
				(size 2.54 2.54)
				(thickness 0.508)
				(bold yes)
			)
			(justify left bottom)
		)
	)
	(text "5V BUCK CONVERTER"
		(exclude_from_sim no)
		(at 91.44 62.23 0)
		(effects
			(font
				(size 2.54 2.54)
				(thickness 0.508)
				(bold yes)
			)
			(justify left bottom)
		)
	)
	(text "1V25 voltage reference DNP"
		(exclude_from_sim no)
		(at 273.05 38.1 0)
		(effects
			(font
				(size 2.54 2.54)
				(thickness 0.508)
				(bold yes)
			)
			(justify left bottom)
		)
	)
	(label "EN_1V8"
		(at 71.12 209.55 0)
		(fields_autoplaced yes)
		(effects
			(font
				(size 1.27 1.27)
			)
			(justify left bottom)
		)
	)
	(label "SW_1V8"
		(at 100.33 204.47 0)
		(fields_autoplaced yes)
		(effects
			(font
				(size 1.27 1.27)
			)
			(justify left bottom)
		)
	)
	(label "OUT_3V3"
		(at 330.2 201.93 0)
		(fields_autoplaced yes)
		(effects
			(font
				(size 1.27 1.27)
			)
			(justify left bottom)
		)
	)
	(label "OUT_5V"
		(at 144.78 81.28 0)
		(fields_autoplaced yes)
		(effects
			(font
				(size 1.27 1.27)
			)
			(justify left bottom)
		)
	)
	(label "FB_3V3"
		(at 302.26 212.09 0)
		(fields_autoplaced yes)
		(effects
			(font
				(size 1.27 1.27)
			)
			(justify left bottom)
		)
	)
	(label "FB_5V"
		(at 116.84 91.44 0)
		(fields_autoplaced yes)
		(effects
			(font
				(size 1.27 1.27)
			)
			(justify left bottom)
		)
	)
	(label "OUT_1V8"
		(at 127 204.47 0)
		(fields_autoplaced yes)
		(effects
			(font
				(size 1.27 1.27)
			)
			(justify left bottom)
		)
	)
	(label "SW_3V3"
		(at 302.26 201.93 0)
		(fields_autoplaced yes)
		(effects
			(font
				(size 1.27 1.27)
			)
			(justify left bottom)
		)
	)
	(label "EN_5V"
		(at 88.9 86.36 0)
		(fields_autoplaced yes)
		(effects
			(font
				(size 1.27 1.27)
			)
			(justify left bottom)
		)
	)
	(label "SW_5V"
		(at 116.84 81.28 0)
		(fields_autoplaced yes)
		(effects
			(font
				(size 1.27 1.27)
			)
			(justify left bottom)
		)
	)
	(label "EN_3V3"
		(at 274.32 207.01 0)
		(fields_autoplaced yes)
		(effects
			(font
				(size 1.27 1.27)
			)
			(justify left bottom)
		)
	)
	(label "FB_1V8"
		(at 100.33 214.63 0)
		(fields_autoplaced yes)
		(effects
			(font
				(size 1.27 1.27)
			)
			(justify left bottom)
		)
	)
	(hierarchical_label "VREF"
		(shape output)
		(at 323.85 54.61 0)
		(fields_autoplaced yes)
		(effects
			(font
				(size 1.27 1.27)
			)
			(justify left)
		)
	)
	(symbol
		(lib_id "antmicroTransistorsFETsMOSFETsSingle:DMG1012T-7")
		(at 165.1 227.33 0)
		(unit 1)
		(exclude_from_sim no)
		(in_bom no)
		(on_board yes)
		(dnp no)
		(fields_autoplaced yes)
		(property "Reference" "Q3"
			(at 175.26 223.52 0)
			(effects
				(font
					(size 1.27 1.27)
					(thickness 0.15)
				)
				(justify left)
			)
		)
		(property "Value" "DMG1012T-7"
			(at 175.26 231.14 0)
			(effects
				(font
					(size 1.27 1.27)
					(thickness 0.15)
				)
				(justify left bottom)
				(hide yes)
			)
		)
		(property "Footprint" "antmicro-footprints:SOT-523"
			(at 175.26 233.68 0)
			(effects
				(font
					(size 1.27 1.27)
					(thickness 0.15)
				)
				(justify left bottom)
				(hide yes)
			)
		)
		(property "Datasheet" "https://www.diodes.com/assets/Datasheets/ds31783.pdf"
			(at 175.26 236.22 0)
			(effects
				(font
					(size 1.27 1.27)
					(thickness 0.15)
				)
				(justify left bottom)
				(hide yes)
			)
		)
		(property "Description" ""
			(at 165.1 227.33 0)
			(effects
				(font
					(size 1.27 1.27)
				)
				(hide yes)
			)
		)
		(property "MPN" "DMG1012T-7"
			(at 175.26 226.06 0)
			(effects
				(font
					(size 1.27 1.27)
					(thickness 0.15)
				)
				(justify left)
			)
		)
		(property "Manufacturer" "Diodes Incorporated"
			(at 175.26 228.6 0)
			(effects
				(font
					(size 1.27 1.27)
					(thickness 0.15)
				)
				(justify left bottom)
				(hide yes)
			)
		)
		(property "Author" "Antmicro"
			(at 175.26 238.76 0)
			(effects
				(font
					(size 1.27 1.27)
					(thickness 0.15)
				)
				(justify left bottom)
				(hide yes)
			)
		)
		(property "License" "Apache-2.0"
			(at 175.26 241.3 0)
			(effects
				(font
					(size 1.27 1.27)
					(thickness 0.15)
				)
				(justify left bottom)
				(hide yes)
			)
		)
		(property "Public" ""
			(at 185.42 234.95 0)
			(effects
				(font
					(size 1.27 1.27)
				)
				(justify left bottom)
				(hide yes)
			)
		)
		(pin "2"
		)
		(pin "3"
		)
		(pin "1"
		)
		(instances
			(project "gmsl-serializer"
				(path ""
					(reference "Q3")
					(unit 1)
				)
			)
		)
	)
	(symbol
		(lib_id "antmicroLEDIndicationDiscrete:LED_G_0603_LTST-C190GKT")
		(at 54.61 87.63 270)
		(mirror x)
		(unit 1)
		(exclude_from_sim no)
		(in_bom yes)
		(on_board yes)
		(dnp no)
		(property "Reference" "D9"
			(at 58.42 83.82 90)
			(effects
				(font
					(size 1.27 1.27)
					(thickness 0.15)
				)
				(justify left)
			)
		)
		(property "Value" "LED_G_0603_LTST-C190GKT"
			(at 26.035 82.55 90)
			(effects
				(font
					(size 1.27 1.27)
					(thickness 0.15)
				)
				(justify left)
				(hide yes)
			)
		)
		(property "Footprint" "antmicro-footprints:LED_0603_1608Metric_G"
			(at 44.45 64.77 0)
			(effects
				(font
					(size 1.27 1.27)
					(thickness 0.15)
				)
				(justify left bottom)
				(hide yes)
			)
		)
		(property "Datasheet" "https://media.digikey.com/pdf/Data%20Sheets/Lite-On%20PDFs/LTST-C190GKT.pdf"
			(at 41.91 64.77 0)
			(effects
				(font
					(size 1.27 1.27)
					(thickness 0.15)
				)
				(justify left bottom)
				(hide yes)
			)
		)
		(property "Description" ""
			(at 54.61 87.63 0)
			(effects
				(font
					(size 1.27 1.27)
				)
				(hide yes)
			)
		)
		(property "MPN" "LTST-C190GKT"
			(at 58.42 85.09 90)
			(effects
				(font
					(size 1.27 1.27)
					(thickness 0.15)
				)
				(justify left bottom)
			)
		)
		(property "Manufacturer" "Lite-On"
			(at 36.83 64.77 0)
			(effects
				(font
					(size 1.27 1.27)
					(thickness 0.15)
				)
				(justify left bottom)
				(hide yes)
			)
		)
		(property "Author" "Antmicro"
			(at 34.29 64.77 0)
			(effects
				(font
					(size 1.27 1.27)
					(thickness 0.15)
				)
				(justify left bottom)
				(hide yes)
			)
		)
		(property "License" "Apache-2.0"
			(at 31.75 64.77 0)
			(effects
				(font
					(size 1.27 1.27)
					(thickness 0.15)
				)
				(justify left bottom)
				(hide yes)
			)
		)
		(property "VSD_class" "LED"
			(at 29.21 64.77 0)
			(effects
				(font
					(size 1.27 1.27)
				)
				(justify left bottom)
				(hide yes)
			)
		)
		(property "Color" "Green"
			(at 49.53 64.77 0)
			(effects
				(font
					(size 1.27 1.27)
				)
				(justify left bottom)
				(hide yes)
			)
		)
		(pin "1"
		)
		(pin "2"
		)
		(instances
			(project "gmsl-serializer"
				(path ""
					(reference "D9")
					(unit 1)
				)
			)
		)
	)
	(symbol
		(lib_id "antmicropower:GND")
		(at 171.45 236.22 0)
		(unit 1)
		(exclude_from_sim no)
		(in_bom yes)
		(on_board yes)
		(dnp no)
		(property "Reference" "#PWR014"
			(at 180.34 238.76 0)
			(effects
				(font
					(size 1.27 1.27)
					(thickness 0.15)
				)
				(justify left bottom)
				(hide yes)
			)
		)
		(property "Value" "GND"
			(at 171.45 240.03 0)
			(effects
				(font
					(size 1.27 1.27)
					(thickness 0.15)
				)
			)
		)
		(property "Footprint" ""
			(at 180.34 243.84 0)
			(effects
				(font
					(size 1.27 1.27)
					(thickness 0.15)
				)
				(justify left bottom)
				(hide yes)
			)
		)
		(property "Datasheet" ""
			(at 180.34 248.92 0)
			(effects
				(font
					(size 1.27 1.27)
					(thickness 0.15)
				)
				(justify left bottom)
				(hide yes)
			)
		)
		(property "Description" ""
			(at 171.45 236.22 0)
			(effects
				(font
					(size 1.27 1.27)
				)
				(hide yes)
			)
		)
		(property "Author" "Antmicro"
			(at 180.34 243.84 0)
			(effects
				(font
					(size 1.27 1.27)
					(thickness 0.15)
				)
				(justify left bottom)
				(hide yes)
			)
		)
		(property "License" "Apache-2.0"
			(at 180.34 246.38 0)
			(effects
				(font
					(size 1.27 1.27)
					(thickness 0.15)
				)
				(justify left bottom)
				(hide yes)
			)
		)
		(pin "1"
		)
		(instances
			(project "gmsl-serializer"
				(path ""
					(reference "#PWR014")
					(unit 1)
				)
			)
		)
	)
	(symbol
		(lib_id "antmicropower:GND")
		(at 261.62 213.36 0)
		(unit 1)
		(exclude_from_sim no)
		(in_bom yes)
		(on_board yes)
		(dnp no)
		(property "Reference" "#PWR022"
			(at 270.51 215.9 0)
			(effects
				(font
					(size 1.27 1.27)
					(thickness 0.15)
				)
				(justify left bottom)
				(hide yes)
			)
		)
		(property "Value" "GND"
			(at 261.62 217.17 0)
			(effects
				(font
					(size 1.27 1.27)
					(thickness 0.15)
				)
			)
		)
		(property "Footprint" ""
			(at 270.51 220.98 0)
			(effects
				(font
					(size 1.27 1.27)
					(thickness 0.15)
				)
				(justify left bottom)
				(hide yes)
			)
		)
		(property "Datasheet" ""
			(at 270.51 226.06 0)
			(effects
				(font
					(size 1.27 1.27)
					(thickness 0.15)
				)
				(justify left bottom)
				(hide yes)
			)
		)
		(property "Description" ""
			(at 261.62 213.36 0)
			(effects
				(font
					(size 1.27 1.27)
				)
				(hide yes)
			)
		)
		(property "Author" "Antmicro"
			(at 270.51 220.98 0)
			(effects
				(font
					(size 1.27 1.27)
					(thickness 0.15)
				)
				(justify left bottom)
				(hide yes)
			)
		)
		(property "License" "Apache-2.0"
			(at 270.51 223.52 0)
			(effects
				(font
					(size 1.27 1.27)
					(thickness 0.15)
				)
				(justify left bottom)
				(hide yes)
			)
		)
		(pin "1"
		)
		(instances
			(project "gmsl-serializer"
				(path ""
					(reference "#PWR022")
					(unit 1)
				)
			)
		)
	)
	(symbol
		(lib_id "antmicroResistors0402:R_10k_0402")
		(at 71.12 215.9 90)
		(unit 1)
		(exclude_from_sim no)
		(in_bom yes)
		(on_board yes)
		(dnp no)
		(fields_autoplaced yes)
		(property "Reference" "R26"
			(at 73.025 212.0899 90)
			(effects
				(font
					(size 1.27 1.27)
					(thickness 0.15)
				)
				(justify right)
			)
		)
		(property "Value" "R_10k_0402"
			(at 83.82 195.58 0)
			(effects
				(font
					(size 1.27 1.27)
					(thickness 0.15)
				)
				(justify left bottom)
				(hide yes)
			)
		)
		(property "Footprint" "antmicro-footprints:R_0402_1005Metric"
			(at 86.36 195.58 0)
			(effects
				(font
					(size 1.27 1.27)
					(thickness 0.15)
				)
				(justify left bottom)
				(hide yes)
			)
		)
		(property "Datasheet" "https://www.bourns.com/docs/product-datasheets/cr.pdf"
			(at 88.9 195.58 0)
			(effects
				(font
					(size 1.27 1.27)
					(thickness 0.15)
				)
				(justify left bottom)
				(hide yes)
			)
		)
		(property "Description" ""
			(at 71.12 215.9 0)
			(effects
				(font
					(size 1.27 1.27)
				)
				(hide yes)
			)
		)
		(property "MPN" "CR0402-FX-1002GLF"
			(at 91.44 195.58 0)
			(effects
				(font
					(size 1.27 1.27)
					(thickness 0.15)
				)
				(justify left bottom)
				(hide yes)
			)
		)
		(property "Manufacturer" "Bourns"
			(at 93.98 195.58 0)
			(effects
				(font
					(size 1.27 1.27)
					(thickness 0.15)
				)
				(justify left bottom)
				(hide yes)
			)
		)
		(property "License" "Apache-2.0"
			(at 96.52 195.58 0)
			(effects
				(font
					(size 1.27 1.27)
					(thickness 0.15)
				)
				(justify left bottom)
				(hide yes)
			)
		)
		(property "Author" "Antmicro"
			(at 99.06 195.58 0)
			(effects
				(font
					(size 1.27 1.27)
					(thickness 0.15)
				)
				(justify left bottom)
				(hide yes)
			)
		)
		(property "Val" "10k"
			(at 73.025 214.6299 90)
			(effects
				(font
					(size 1.27 1.27)
					(thickness 0.15)
				)
				(justify right)
			)
		)
		(property "Tolerance" "1%"
			(at 81.28 195.58 0)
			(effects
				(font
					(size 1.27 1.27)
				)
				(justify left bottom)
				(hide yes)
			)
		)
		(pin "1"
		)
		(pin "2"
		)
		(instances
			(project "gmsl-serializer"
				(path ""
					(reference "R26")
					(unit 1)
				)
			)
		)
	)
	(symbol
		(lib_id "antmicroPMICVoltageRegulatorsLinear:TLV73312PDBVT")
		(at 279.4 127 0)
		(unit 1)
		(exclude_from_sim no)
		(in_bom yes)
		(on_board yes)
		(dnp no)
		(fields_autoplaced yes)
		(property "Reference" "U5"
			(at 289.56 119.38 0)
			(effects
				(font
					(size 1.27 1.27)
					(thickness 0.15)
				)
			)
		)
		(property "Value" "TLV73312PDBVT"
			(at 289.56 121.92 0)
			(effects
				(font
					(size 1.27 1.27)
					(thickness 0.15)
				)
				(hide yes)
			)
		)
		(property "Footprint" "antmicro-footprints:SOT-23-5"
			(at 314.96 134.62 0)
			(effects
				(font
					(size 1.27 1.27)
					(thickness 0.15)
				)
				(justify left bottom)
				(hide yes)
			)
		)
		(property "Datasheet" "https://www.ti.com/lit/ds/symlink/tlv733p.pdf?HQS=dis-mous-null-mousermode-dsf-pf-null-wwe&ts=1676978230940&ref_url=https%253A%252F%252Fwww.mouser.com%252F"
			(at 314.96 137.16 0)
			(effects
				(font
					(size 1.27 1.27)
					(thickness 0.15)
				)
				(justify left bottom)
				(hide yes)
			)
		)
		(property "Description" ""
			(at 279.4 127 0)
			(effects
				(font
					(size 1.27 1.27)
				)
				(hide yes)
			)
		)
		(property "MPN" "TLV73312PDBVT"
			(at 289.56 121.92 0)
			(effects
				(font
					(size 1.27 1.27)
					(thickness 0.15)
				)
			)
		)
		(property "Manufacturer" "Texas Instruments"
			(at 314.96 142.24 0)
			(effects
				(font
					(size 1.27 1.27)
					(thickness 0.15)
				)
				(justify left bottom)
				(hide yes)
			)
		)
		(property "Author" "Antmicro"
			(at 314.96 144.78 0)
			(effects
				(font
					(size 1.27 1.27)
					(thickness 0.15)
				)
				(justify left bottom)
				(hide yes)
			)
		)
		(property "License" "Apache-2.0"
			(at 314.96 147.32 0)
			(effects
				(font
					(size 1.27 1.27)
					(thickness 0.15)
				)
				(justify left bottom)
				(hide yes)
			)
		)
		(pin "1"
		)
		(pin "2"
		)
		(pin "3"
		)
		(pin "4"
		)
		(pin "5"
		)
		(instances
			(project "gmsl-serializer"
				(path ""
					(reference "U5")
					(unit 1)
				)
			)
		)
	)
	(symbol
		(lib_id "antmicropower:GND")
		(at 351.79 139.7 0)
		(unit 1)
		(exclude_from_sim no)
		(in_bom yes)
		(on_board yes)
		(dnp no)
		(property "Reference" "#PWR06"
			(at 360.68 142.24 0)
			(effects
				(font
					(size 1.27 1.27)
					(thickness 0.15)
				)
				(justify left bottom)
				(hide yes)
			)
		)
		(property "Value" "GND"
			(at 351.79 143.51 0)
			(effects
				(font
					(size 1.27 1.27)
					(thickness 0.15)
				)
			)
		)
		(property "Footprint" ""
			(at 360.68 147.32 0)
			(effects
				(font
					(size 1.27 1.27)
					(thickness 0.15)
				)
				(justify left bottom)
				(hide yes)
			)
		)
		(property "Datasheet" ""
			(at 360.68 152.4 0)
			(effects
				(font
					(size 1.27 1.27)
					(thickness 0.15)
				)
				(justify left bottom)
				(hide yes)
			)
		)
		(property "Description" ""
			(at 351.79 139.7 0)
			(effects
				(font
					(size 1.27 1.27)
				)
				(hide yes)
			)
		)
		(property "Author" "Antmicro"
			(at 360.68 147.32 0)
			(effects
				(font
					(size 1.27 1.27)
					(thickness 0.15)
				)
				(justify left bottom)
				(hide yes)
			)
		)
		(property "License" "Apache-2.0"
			(at 360.68 149.86 0)
			(effects
				(font
					(size 1.27 1.27)
					(thickness 0.15)
				)
				(justify left bottom)
				(hide yes)
			)
		)
		(pin "1"
		)
		(instances
			(project "gmsl-serializer"
				(path ""
					(reference "#PWR06")
					(unit 1)
				)
			)
		)
	)
	(symbol
		(lib_id "antmicropower:PWR_FLAG")
		(at 261.62 200.66 0)
		(unit 1)
		(exclude_from_sim no)
		(in_bom yes)
		(on_board yes)
		(dnp no)
		(property "Reference" "#FLG04"
			(at 261.62 198.755 0)
			(effects
				(font
					(size 1.27 1.27)
				)
				(hide yes)
			)
		)
		(property "Value" "PWR_FLAG"
			(at 261.62 196.85 0)
			(effects
				(font
					(size 1.27 1.27)
				)
			)
		)
		(property "Footprint" ""
			(at 261.62 200.66 0)
			(effects
				(font
					(size 1.27 1.27)
				)
				(hide yes)
			)
		)
		(property "Datasheet" ""
			(at 261.62 200.66 0)
			(effects
				(font
					(size 1.27 1.27)
				)
				(hide yes)
			)
		)
		(property "Description" ""
			(at 261.62 200.66 0)
			(effects
				(font
					(size 1.27 1.27)
				)
				(hide yes)
			)
		)
		(pin "1"
		)
		(instances
			(project "gmsl-serializer"
				(path ""
					(reference "#FLG04")
					(unit 1)
				)
			)
		)
	)
	(symbol
		(lib_id "antmicroCapacitors0603:C_10u_25V_0603")
		(at 55.88 214.63 90)
		(unit 1)
		(exclude_from_sim no)
		(in_bom yes)
		(on_board yes)
		(dnp no)
		(fields_autoplaced yes)
		(property "Reference" "C2"
			(at 58.42 210.8135 90)
			(effects
				(font
					(size 1.27 1.27)
					(thickness 0.15)
				)
				(justify right)
			)
		)
		(property "Value" "C_10u_25V_0603"
			(at 66.04 194.31 0)
			(effects
				(font
					(size 1.27 1.27)
					(thickness 0.15)
				)
				(justify left bottom)
				(hide yes)
			)
		)
		(property "Footprint" "antmicro-footprints:C_0603_1608Metric"
			(at 68.58 194.31 0)
			(effects
				(font
					(size 1.27 1.27)
					(thickness 0.15)
				)
				(justify left bottom)
				(hide yes)
			)
		)
		(property "Datasheet" "https://product.tdk.com/en/search/capacitor/ceramic/mlcc/info?part_no=C1608X5R1E106M080AC"
			(at 71.12 194.31 0)
			(effects
				(font
					(size 1.27 1.27)
					(thickness 0.15)
				)
				(justify left bottom)
				(hide yes)
			)
		)
		(property "Description" ""
			(at 55.88 214.63 0)
			(effects
				(font
					(size 1.27 1.27)
				)
				(hide yes)
			)
		)
		(property "MPN" "C1608X5R1E106M080AC"
			(at 73.66 194.31 0)
			(effects
				(font
					(size 1.27 1.27)
					(thickness 0.15)
				)
				(justify left bottom)
				(hide yes)
			)
		)
		(property "Manufacturer" "TDK"
			(at 76.2 194.31 0)
			(effects
				(font
					(size 1.27 1.27)
					(thickness 0.15)
				)
				(justify left bottom)
				(hide yes)
			)
		)
		(property "License" "Apache-2.0"
			(at 78.74 194.31 0)
			(effects
				(font
					(size 1.27 1.27)
					(thickness 0.15)
				)
				(justify left bottom)
				(hide yes)
			)
		)
		(property "Author" "Antmicro"
			(at 81.28 194.31 0)
			(effects
				(font
					(size 1.27 1.27)
					(thickness 0.15)
				)
				(justify left bottom)
				(hide yes)
			)
		)
		(property "Val" "10u"
			(at 58.42 213.3535 90)
			(effects
				(font
					(size 1.27 1.27)
					(thickness 0.15)
				)
				(justify right)
			)
		)
		(property "Voltage" "25V"
			(at 83.82 194.31 0)
			(effects
				(font
					(size 1.27 1.27)
				)
				(justify left bottom)
				(hide yes)
			)
		)
		(property "Dielectric" ""
			(at 86.36 194.31 0)
			(effects
				(font
					(size 1.27 1.27)
				)
				(justify left bottom)
				(hide yes)
			)
		)
		(pin "1"
		)
		(pin "2"
		)
		(instances
			(project "gmsl-serializer"
				(path ""
					(reference "C2")
					(unit 1)
				)
			)
		)
	)
	(symbol
		(lib_id "antmicropower:PWR_FLAG")
		(at 257.81 213.36 180)
		(unit 1)
		(exclude_from_sim no)
		(in_bom yes)
		(on_board yes)
		(dnp no)
		(property "Reference" "#FLG03"
			(at 257.81 215.265 0)
			(effects
				(font
					(size 1.27 1.27)
				)
				(hide yes)
			)
		)
		(property "Value" "PWR_FLAG"
			(at 254 217.805 0)
			(effects
				(font
					(size 1.27 1.27)
				)
			)
		)
		(property "Footprint" ""
			(at 257.81 213.36 0)
			(effects
				(font
					(size 1.27 1.27)
				)
				(hide yes)
			)
		)
		(property "Datasheet" ""
			(at 257.81 213.36 0)
			(effects
				(font
					(size 1.27 1.27)
				)
				(hide yes)
			)
		)
		(property "Description" ""
			(at 257.81 213.36 0)
			(effects
				(font
					(size 1.27 1.27)
				)
				(hide yes)
			)
		)
		(pin "1"
		)
		(instances
			(project "gmsl-serializer"
				(path ""
					(reference "#FLG03")
					(unit 1)
				)
			)
		)
	)
	(symbol
		(lib_id "antmicroTransistorsFETsMOSFETsSingle:DMG1012T-7")
		(at 345.44 130.81 0)
		(unit 1)
		(exclude_from_sim no)
		(in_bom no)
		(on_board yes)
		(dnp no)
		(fields_autoplaced yes)
		(property "Reference" "Q1"
			(at 355.6 127 0)
			(effects
				(font
					(size 1.27 1.27)
					(thickness 0.15)
				)
				(justify left)
			)
		)
		(property "Value" "DMG1012T-7"
			(at 355.6 134.62 0)
			(effects
				(font
					(size 1.27 1.27)
					(thickness 0.15)
				)
				(justify left bottom)
				(hide yes)
			)
		)
		(property "Footprint" "antmicro-footprints:SOT-523"
			(at 355.6 137.16 0)
			(effects
				(font
					(size 1.27 1.27)
					(thickness 0.15)
				)
				(justify left bottom)
				(hide yes)
			)
		)
		(property "Datasheet" "https://www.diodes.com/assets/Datasheets/ds31783.pdf"
			(at 355.6 139.7 0)
			(effects
				(font
					(size 1.27 1.27)
					(thickness 0.15)
				)
				(justify left bottom)
				(hide yes)
			)
		)
		(property "Description" ""
			(at 345.44 130.81 0)
			(effects
				(font
					(size 1.27 1.27)
				)
				(hide yes)
			)
		)
		(property "MPN" "DMG1012T-7"
			(at 355.6 129.54 0)
			(effects
				(font
					(size 1.27 1.27)
					(thickness 0.15)
				)
				(justify left)
			)
		)
		(property "Manufacturer" "Diodes Incorporated"
			(at 355.6 132.08 0)
			(effects
				(font
					(size 1.27 1.27)
					(thickness 0.15)
				)
				(justify left bottom)
				(hide yes)
			)
		)
		(property "Author" "Antmicro"
			(at 355.6 142.24 0)
			(effects
				(font
					(size 1.27 1.27)
					(thickness 0.15)
				)
				(justify left bottom)
				(hide yes)
			)
		)
		(property "License" "Apache-2.0"
			(at 355.6 144.78 0)
			(effects
				(font
					(size 1.27 1.27)
					(thickness 0.15)
				)
				(justify left bottom)
				(hide yes)
			)
		)
		(property "Public" ""
			(at 365.76 138.43 0)
			(effects
				(font
					(size 1.27 1.27)
				)
				(justify left bottom)
				(hide yes)
			)
		)
		(pin "2"
		)
		(pin "3"
		)
		(pin "1"
		)
		(instances
			(project "gmsl-serializer"
				(path ""
					(reference "Q1")
					(unit 1)
				)
			)
		)
	)
	(symbol
		(lib_id "antmicropower:GND")
		(at 153.67 99.06 0)
		(unit 1)
		(exclude_from_sim no)
		(in_bom yes)
		(on_board yes)
		(dnp no)
		(property "Reference" "#PWR0130"
			(at 162.56 101.6 0)
			(effects
				(font
					(size 1.27 1.27)
					(thickness 0.15)
				)
				(justify left bottom)
				(hide yes)
			)
		)
		(property "Value" "GND"
			(at 153.67 102.87 0)
			(effects
				(font
					(size 1.27 1.27)
					(thickness 0.15)
				)
			)
		)
		(property "Footprint" ""
			(at 162.56 106.68 0)
			(effects
				(font
					(size 1.27 1.27)
					(thickness 0.15)
				)
				(justify left bottom)
				(hide yes)
			)
		)
		(property "Datasheet" ""
			(at 162.56 111.76 0)
			(effects
				(font
					(size 1.27 1.27)
					(thickness 0.15)
				)
				(justify left bottom)
				(hide yes)
			)
		)
		(property "Description" ""
			(at 153.67 99.06 0)
			(effects
				(font
					(size 1.27 1.27)
				)
				(hide yes)
			)
		)
		(property "Author" "Antmicro"
			(at 162.56 106.68 0)
			(effects
				(font
					(size 1.27 1.27)
					(thickness 0.15)
				)
				(justify left bottom)
				(hide yes)
			)
		)
		(property "License" "Apache-2.0"
			(at 162.56 109.22 0)
			(effects
				(font
					(size 1.27 1.27)
					(thickness 0.15)
				)
				(justify left bottom)
				(hide yes)
			)
		)
		(pin "1"
		)
		(instances
			(project "gmsl-serializer"
				(path ""
					(reference "#PWR0130")
					(unit 1)
				)
			)
		)
	)
	(symbol
		(lib_id "antmicropower:PWR_FLAG")
		(at 72.39 92.71 180)
		(unit 1)
		(exclude_from_sim no)
		(in_bom yes)
		(on_board yes)
		(dnp no)
		(property "Reference" "#FLG0104"
			(at 72.39 94.615 0)
			(effects
				(font
					(size 1.27 1.27)
				)
				(hide yes)
			)
		)
		(property "Value" "PWR_FLAG"
			(at 68.58 97.155 0)
			(effects
				(font
					(size 1.27 1.27)
				)
			)
		)
		(property "Footprint" ""
			(at 72.39 92.71 0)
			(effects
				(font
					(size 1.27 1.27)
				)
				(hide yes)
			)
		)
		(property "Datasheet" ""
			(at 72.39 92.71 0)
			(effects
				(font
					(size 1.27 1.27)
				)
				(hide yes)
			)
		)
		(property "Description" ""
			(at 72.39 92.71 0)
			(effects
				(font
					(size 1.27 1.27)
				)
				(hide yes)
			)
		)
		(pin "1"
		)
		(instances
			(project "gmsl-serializer"
				(path ""
					(reference "#FLG0104")
					(unit 1)
				)
			)
		)
	)
	(symbol
		(lib_id "antmicropower:GND")
		(at 135.89 99.06 0)
		(unit 1)
		(exclude_from_sim no)
		(in_bom yes)
		(on_board yes)
		(dnp no)
		(property "Reference" "#PWR0128"
			(at 144.78 101.6 0)
			(effects
				(font
					(size 1.27 1.27)
					(thickness 0.15)
				)
				(justify left bottom)
				(hide yes)
			)
		)
		(property "Value" "GND"
			(at 135.89 102.87 0)
			(effects
				(font
					(size 1.27 1.27)
					(thickness 0.15)
				)
			)
		)
		(property "Footprint" ""
			(at 144.78 106.68 0)
			(effects
				(font
					(size 1.27 1.27)
					(thickness 0.15)
				)
				(justify left bottom)
				(hide yes)
			)
		)
		(property "Datasheet" ""
			(at 144.78 111.76 0)
			(effects
				(font
					(size 1.27 1.27)
					(thickness 0.15)
				)
				(justify left bottom)
				(hide yes)
			)
		)
		(property "Description" ""
			(at 135.89 99.06 0)
			(effects
				(font
					(size 1.27 1.27)
				)
				(hide yes)
			)
		)
		(property "Author" "Antmicro"
			(at 144.78 106.68 0)
			(effects
				(font
					(size 1.27 1.27)
					(thickness 0.15)
				)
				(justify left bottom)
				(hide yes)
			)
		)
		(property "License" "Apache-2.0"
			(at 144.78 109.22 0)
			(effects
				(font
					(size 1.27 1.27)
					(thickness 0.15)
				)
				(justify left bottom)
				(hide yes)
			)
		)
		(pin "1"
		)
		(instances
			(project "gmsl-serializer"
				(path ""
					(reference "#PWR0128")
					(unit 1)
				)
			)
		)
	)
	(symbol
		(lib_id "antmicroResistors0402:R_1k65_0402")
		(at 54.61 93.98 90)
		(unit 1)
		(exclude_from_sim no)
		(in_bom yes)
		(on_board yes)
		(dnp no)
		(fields_autoplaced yes)
		(property "Reference" "R40"
			(at 57.15 90.17 90)
			(effects
				(font
					(size 1.27 1.27)
					(thickness 0.15)
				)
				(justify right)
			)
		)
		(property "Value" "R_1k65_0402"
			(at 67.31 73.66 0)
			(effects
				(font
					(size 1.27 1.27)
					(thickness 0.15)
				)
				(justify left bottom)
				(hide yes)
			)
		)
		(property "Footprint" "antmicro-footprints:R_0402_1005Metric"
			(at 69.85 73.66 0)
			(effects
				(font
					(size 1.27 1.27)
					(thickness 0.15)
				)
				(justify left bottom)
				(hide yes)
			)
		)
		(property "Datasheet" "https://www.farnell.com/datasheets/3795017.pdf"
			(at 72.39 73.66 0)
			(effects
				(font
					(size 1.27 1.27)
					(thickness 0.15)
				)
				(justify left bottom)
				(hide yes)
			)
		)
		(property "Description" ""
			(at 54.61 93.98 0)
			(effects
				(font
					(size 1.27 1.27)
				)
				(hide yes)
			)
		)
		(property "MPN" "RC0402FR-071K65L"
			(at 74.93 73.66 0)
			(effects
				(font
					(size 1.27 1.27)
					(thickness 0.15)
				)
				(justify left bottom)
				(hide yes)
			)
		)
		(property "Manufacturer" "YAGEO"
			(at 77.47 73.66 0)
			(effects
				(font
					(size 1.27 1.27)
					(thickness 0.15)
				)
				(justify left bottom)
				(hide yes)
			)
		)
		(property "License" "Apache-2.0"
			(at 80.01 73.66 0)
			(effects
				(font
					(size 1.27 1.27)
					(thickness 0.15)
				)
				(justify left bottom)
				(hide yes)
			)
		)
		(property "Author" "Antmicro"
			(at 82.55 73.66 0)
			(effects
				(font
					(size 1.27 1.27)
					(thickness 0.15)
				)
				(justify left bottom)
				(hide yes)
			)
		)
		(property "Val" "1k65"
			(at 57.15 92.71 90)
			(effects
				(font
					(size 1.27 1.27)
					(thickness 0.15)
				)
				(justify right)
			)
		)
		(property "Tolerance" "1%"
			(at 64.77 73.66 0)
			(effects
				(font
					(size 1.27 1.27)
				)
				(justify left bottom)
				(hide yes)
			)
		)
		(property "Public" ""
			(at 85.09 73.66 0)
			(effects
				(font
					(size 1.27 1.27)
				)
				(justify left bottom)
				(hide yes)
			)
		)
		(pin "1"
		)
		(pin "2"
		)
		(instances
			(project "gmsl-serializer"
				(path ""
					(reference "R40")
					(unit 1)
				)
			)
		)
	)
	(symbol
		(lib_id "antmicroTestPoints:TP_1.5mm_SMD")
		(at 158.75 204.47 0)
		(unit 1)
		(exclude_from_sim no)
		(in_bom no)
		(on_board yes)
		(dnp no)
		(property "Reference" "TP2"
			(at 163.83 201.93 0)
			(effects
				(font
					(size 1.27 1.27)
					(thickness 0.15)
				)
				(justify right)
			)
		)
		(property "Value" "TP_1.5mm_SMD"
			(at 173.99 212.09 0)
			(effects
				(font
					(size 1.27 1.27)
					(thickness 0.15)
				)
				(justify left bottom)
				(hide yes)
			)
		)
		(property "Footprint" "antmicro-footprints:TP_SMD_1.5mm"
			(at 173.99 214.63 0)
			(effects
				(font
					(size 1.27 1.27)
					(thickness 0.15)
				)
				(justify left bottom)
				(hide yes)
			)
		)
		(property "Datasheet" ""
			(at 176.53 217.17 0)
			(effects
				(font
					(size 1.27 1.27)
					(thickness 0.15)
				)
				(justify left bottom)
				(hide yes)
			)
		)
		(property "Description" ""
			(at 158.75 204.47 0)
			(effects
				(font
					(size 1.27 1.27)
				)
				(hide yes)
			)
		)
		(property "MPN" ""
			(at 158.75 204.47 0)
			(effects
				(font
					(size 1.27 1.27)
				)
				(hide yes)
			)
		)
		(property "Manufacturer" ""
			(at 158.75 204.47 0)
			(effects
				(font
					(size 1.27 1.27)
				)
				(hide yes)
			)
		)
		(property "Author" "Antmicro"
			(at 173.99 219.71 0)
			(effects
				(font
					(size 1.27 1.27)
					(thickness 0.15)
				)
				(justify left bottom)
				(hide yes)
			)
		)
		(property "License" "Apache-2.0"
			(at 173.99 222.25 0)
			(effects
				(font
					(size 1.27 1.27)
					(thickness 0.15)
				)
				(justify left bottom)
				(hide yes)
			)
		)
		(pin "1"
		)
		(instances
			(project "gmsl-serializer"
				(path ""
					(reference "TP2")
					(unit 1)
				)
			)
		)
	)
	(symbol
		(lib_id "antmicroResistors0402:R_470R_0402")
		(at 351.79 113.03 90)
		(unit 1)
		(exclude_from_sim no)
		(in_bom yes)
		(on_board yes)
		(dnp no)
		(fields_autoplaced yes)
		(property "Reference" "R35"
			(at 354.33 109.2199 90)
			(effects
				(font
					(size 1.27 1.27)
					(thickness 0.15)
				)
				(justify right)
			)
		)
		(property "Value" "R_470R_0402"
			(at 364.49 92.71 0)
			(effects
				(font
					(size 1.27 1.27)
					(thickness 0.15)
				)
				(justify left bottom)
				(hide yes)
			)
		)
		(property "Footprint" "antmicro-footprints:R_0402_1005Metric"
			(at 367.03 92.71 0)
			(effects
				(font
					(size 1.27 1.27)
					(thickness 0.15)
				)
				(justify left bottom)
				(hide yes)
			)
		)
		(property "Datasheet" "https://www.bourns.com/docs/product-datasheets/cr.pdf"
			(at 369.57 92.71 0)
			(effects
				(font
					(size 1.27 1.27)
					(thickness 0.15)
				)
				(justify left bottom)
				(hide yes)
			)
		)
		(property "Description" ""
			(at 351.79 113.03 0)
			(effects
				(font
					(size 1.27 1.27)
				)
				(hide yes)
			)
		)
		(property "MPN" "CR0402-FX-4700GLF"
			(at 372.11 92.71 0)
			(effects
				(font
					(size 1.27 1.27)
					(thickness 0.15)
				)
				(justify left bottom)
				(hide yes)
			)
		)
		(property "Manufacturer" "Bourns"
			(at 374.65 92.71 0)
			(effects
				(font
					(size 1.27 1.27)
					(thickness 0.15)
				)
				(justify left bottom)
				(hide yes)
			)
		)
		(property "License" "Apache-2.0"
			(at 377.19 92.71 0)
			(effects
				(font
					(size 1.27 1.27)
					(thickness 0.15)
				)
				(justify left bottom)
				(hide yes)
			)
		)
		(property "Author" "Antmicro"
			(at 379.73 92.71 0)
			(effects
				(font
					(size 1.27 1.27)
					(thickness 0.15)
				)
				(justify left bottom)
				(hide yes)
			)
		)
		(property "Val" "470R"
			(at 354.33 111.7599 90)
			(effects
				(font
					(size 1.27 1.27)
					(thickness 0.15)
				)
				(justify right)
			)
		)
		(property "Tolerance" "1%"
			(at 361.95 92.71 0)
			(effects
				(font
					(size 1.27 1.27)
				)
				(justify left bottom)
				(hide yes)
			)
		)
		(pin "1"
		)
		(pin "2"
		)
		(instances
			(project "gmsl-serializer"
				(path ""
					(reference "R35")
					(unit 1)
				)
			)
		)
	)
	(symbol
		(lib_id "antmicropower:GND")
		(at 321.31 219.71 0)
		(unit 1)
		(exclude_from_sim no)
		(in_bom yes)
		(on_board yes)
		(dnp no)
		(property "Reference" "#PWR026"
			(at 330.2 222.25 0)
			(effects
				(font
					(size 1.27 1.27)
					(thickness 0.15)
				)
				(justify left bottom)
				(hide yes)
			)
		)
		(property "Value" "GND"
			(at 321.31 223.52 0)
			(effects
				(font
					(size 1.27 1.27)
					(thickness 0.15)
				)
			)
		)
		(property "Footprint" ""
			(at 330.2 227.33 0)
			(effects
				(font
					(size 1.27 1.27)
					(thickness 0.15)
				)
				(justify left bottom)
				(hide yes)
			)
		)
		(property "Datasheet" ""
			(at 330.2 232.41 0)
			(effects
				(font
					(size 1.27 1.27)
					(thickness 0.15)
				)
				(justify left bottom)
				(hide yes)
			)
		)
		(property "Description" ""
			(at 321.31 219.71 0)
			(effects
				(font
					(size 1.27 1.27)
				)
				(hide yes)
			)
		)
		(property "Author" "Antmicro"
			(at 330.2 227.33 0)
			(effects
				(font
					(size 1.27 1.27)
					(thickness 0.15)
				)
				(justify left bottom)
				(hide yes)
			)
		)
		(property "License" "Apache-2.0"
			(at 330.2 229.87 0)
			(effects
				(font
					(size 1.27 1.27)
					(thickness 0.15)
				)
				(justify left bottom)
				(hide yes)
			)
		)
		(pin "1"
		)
		(instances
			(project "gmsl-serializer"
				(path ""
					(reference "#PWR026")
					(unit 1)
				)
			)
		)
	)
	(symbol
		(lib_id "antmicroResistors0603:R_0R_22.4A_0603")
		(at 154.94 81.28 0)
		(unit 1)
		(exclude_from_sim no)
		(in_bom yes)
		(on_board yes)
		(dnp no)
		(property "Reference" "R13"
			(at 157.48 76.2 0)
			(effects
				(font
					(size 1.27 1.27)
					(thickness 0.15)
				)
			)
		)
		(property "Value" "R_0R_22.4A_0603"
			(at 157.48 75.565 0)
			(effects
				(font
					(size 1.27 1.27)
					(thickness 0.15)
				)
				(hide yes)
			)
		)
		(property "Footprint" "antmicro-footprints:R_0603_1608Metric"
			(at 170.18 91.44 0)
			(effects
				(font
					(size 1.27 1.27)
					(thickness 0.15)
				)
				(justify left bottom)
				(hide yes)
			)
		)
		(property "Datasheet" "https://fscdn.rohm.com/en/products/databook/datasheet/passive/resistor/chip_resistor/pmr-jpw-e.pdf"
			(at 170.18 93.98 0)
			(effects
				(font
					(size 1.27 1.27)
					(thickness 0.15)
				)
				(justify left bottom)
				(hide yes)
			)
		)
		(property "Description" ""
			(at 154.94 81.28 0)
			(effects
				(font
					(size 1.27 1.27)
				)
				(hide yes)
			)
		)
		(property "MPN" "PMR03EZPJ000"
			(at 170.18 96.52 0)
			(effects
				(font
					(size 1.27 1.27)
					(thickness 0.15)
				)
				(justify left bottom)
				(hide yes)
			)
		)
		(property "Manufacturer" "ROHM Semiconductor"
			(at 170.18 99.06 0)
			(effects
				(font
					(size 1.27 1.27)
					(thickness 0.15)
				)
				(justify left bottom)
				(hide yes)
			)
		)
		(property "Val" "0R"
			(at 157.48 78.74 0)
			(effects
				(font
					(size 1.27 1.27)
					(thickness 0.15)
				)
			)
		)
		(property "Max. Curr." "22.4A"
			(at 157.48 83.82 0)
			(effects
				(font
					(size 1.27 1.27)
					(thickness 0.15)
				)
			)
		)
		(property "Author" "Antmicro"
			(at 170.18 104.14 0)
			(effects
				(font
					(size 1.27 1.27)
					(thickness 0.15)
				)
				(justify left bottom)
				(hide yes)
			)
		)
		(property "License" "Apache-2.0"
			(at 170.18 106.68 0)
			(effects
				(font
					(size 1.27 1.27)
					(thickness 0.15)
				)
				(justify left bottom)
				(hide yes)
			)
		)
		(property "Tolerance" "template_tolerance"
			(at 175.26 91.44 0)
			(effects
				(font
					(size 1.27 1.27)
				)
				(justify left bottom)
				(hide yes)
			)
		)
		(pin "1"
		)
		(pin "2"
		)
		(instances
			(project "gmsl-serializer"
				(path ""
					(reference "R13")
					(unit 1)
				)
			)
		)
	)
	(symbol
		(lib_id "antmicropower:+5V")
		(at 171.45 203.2 0)
		(unit 1)
		(exclude_from_sim no)
		(in_bom yes)
		(on_board yes)
		(dnp no)
		(property "Reference" "#PWR013"
			(at 186.69 205.74 0)
			(effects
				(font
					(size 1.27 1.27)
					(thickness 0.15)
				)
				(justify left bottom)
				(hide yes)
			)
		)
		(property "Value" "+5V"
			(at 171.45 199.39 0)
			(effects
				(font
					(size 1.27 1.27)
					(thickness 0.15)
				)
			)
		)
		(property "Footprint" ""
			(at 186.69 210.82 0)
			(effects
				(font
					(size 1.27 1.27)
					(thickness 0.15)
				)
				(justify left bottom)
				(hide yes)
			)
		)
		(property "Datasheet" ""
			(at 186.69 213.36 0)
			(effects
				(font
					(size 1.27 1.27)
					(thickness 0.15)
				)
				(justify left bottom)
				(hide yes)
			)
		)
		(property "Description" ""
			(at 171.45 203.2 0)
			(effects
				(font
					(size 1.27 1.27)
				)
				(hide yes)
			)
		)
		(property "Author" "Antmicro"
			(at 186.69 210.82 0)
			(effects
				(font
					(size 1.27 1.27)
					(thickness 0.15)
				)
				(justify left bottom)
				(hide yes)
			)
		)
		(property "License" "Apache-2.0"
			(at 186.69 213.36 0)
			(effects
				(font
					(size 1.27 1.27)
					(thickness 0.15)
				)
				(justify left bottom)
				(hide yes)
			)
		)
		(pin "1"
		)
		(instances
			(project "gmsl-serializer"
				(path ""
					(reference "#PWR013")
					(unit 1)
				)
			)
		)
	)
	(symbol
		(lib_id "antmicroCapacitors0402:C_22u_0402")
		(at 339.09 218.44 90)
		(unit 1)
		(exclude_from_sim no)
		(in_bom yes)
		(on_board yes)
		(dnp no)
		(property "Reference" "C35"
			(at 341.63 214.63 90)
			(effects
				(font
					(size 1.27 1.27)
					(thickness 0.15)
				)
				(justify right)
			)
		)
		(property "Value" "C_22u_0402"
			(at 349.25 198.12 0)
			(effects
				(font
					(size 1.27 1.27)
					(thickness 0.15)
				)
				(justify left bottom)
				(hide yes)
			)
		)
		(property "Footprint" "antmicro-footprints:C_0402_1005Metric"
			(at 351.79 198.12 0)
			(effects
				(font
					(size 1.27 1.27)
					(thickness 0.15)
				)
				(justify left bottom)
				(hide yes)
			)
		)
		(property "Datasheet" "https://www.murata.com/products/productdetail?partno=GRM158R60J226ME01%23"
			(at 354.33 198.12 0)
			(effects
				(font
					(size 1.27 1.27)
					(thickness 0.15)
				)
				(justify left bottom)
				(hide yes)
			)
		)
		(property "Description" ""
			(at 339.09 218.44 0)
			(effects
				(font
					(size 1.27 1.27)
				)
				(hide yes)
			)
		)
		(property "MPN" "GRM158R60J226ME01D"
			(at 356.87 198.12 0)
			(effects
				(font
					(size 1.27 1.27)
					(thickness 0.15)
				)
				(justify left bottom)
				(hide yes)
			)
		)
		(property "Manufacturer" "Murata"
			(at 359.41 198.12 0)
			(effects
				(font
					(size 1.27 1.27)
					(thickness 0.15)
				)
				(justify left bottom)
				(hide yes)
			)
		)
		(property "License" "Apache-2.0"
			(at 361.95 198.12 0)
			(effects
				(font
					(size 1.27 1.27)
					(thickness 0.15)
				)
				(justify left bottom)
				(hide yes)
			)
		)
		(property "Author" "Antmicro"
			(at 364.49 198.12 0)
			(effects
				(font
					(size 1.27 1.27)
					(thickness 0.15)
				)
				(justify left bottom)
				(hide yes)
			)
		)
		(property "Val" "22u"
			(at 341.63 217.17 90)
			(effects
				(font
					(size 1.27 1.27)
					(thickness 0.15)
				)
				(justify right)
			)
		)
		(property "Voltage" ""
			(at 367.03 198.12 0)
			(effects
				(font
					(size 1.27 1.27)
				)
				(justify left bottom)
				(hide yes)
			)
		)
		(property "Dielectric" ""
			(at 369.57 198.12 0)
			(effects
				(font
					(size 1.27 1.27)
				)
				(justify left bottom)
				(hide yes)
			)
		)
		(pin "1"
		)
		(pin "2"
		)
		(instances
			(project "gmsl-serializer"
				(path ""
					(reference "C35")
					(unit 1)
				)
			)
		)
	)
	(symbol
		(lib_id "antmicroLEDIndicationDiscrete:LED_G_0603_LTST-C190GKT")
		(at 350.52 212.09 270)
		(mirror x)
		(unit 1)
		(exclude_from_sim no)
		(in_bom yes)
		(on_board yes)
		(dnp no)
		(property "Reference" "D11"
			(at 354.33 208.28 90)
			(effects
				(font
					(size 1.27 1.27)
					(thickness 0.15)
				)
				(justify left)
			)
		)
		(property "Value" "LED_G_0603_LTST-C190GKT"
			(at 321.945 207.01 90)
			(effects
				(font
					(size 1.27 1.27)
					(thickness 0.15)
				)
				(justify left)
				(hide yes)
			)
		)
		(property "Footprint" "antmicro-footprints:LED_0603_1608Metric_G"
			(at 340.36 189.23 0)
			(effects
				(font
					(size 1.27 1.27)
					(thickness 0.15)
				)
				(justify left bottom)
				(hide yes)
			)
		)
		(property "Datasheet" "https://media.digikey.com/pdf/Data%20Sheets/Lite-On%20PDFs/LTST-C190GKT.pdf"
			(at 337.82 189.23 0)
			(effects
				(font
					(size 1.27 1.27)
					(thickness 0.15)
				)
				(justify left bottom)
				(hide yes)
			)
		)
		(property "Description" ""
			(at 350.52 212.09 0)
			(effects
				(font
					(size 1.27 1.27)
				)
				(hide yes)
			)
		)
		(property "MPN" "LTST-C190GKT"
			(at 354.33 209.55 90)
			(effects
				(font
					(size 1.27 1.27)
					(thickness 0.15)
				)
				(justify left bottom)
			)
		)
		(property "Manufacturer" "Lite-On"
			(at 332.74 189.23 0)
			(effects
				(font
					(size 1.27 1.27)
					(thickness 0.15)
				)
				(justify left bottom)
				(hide yes)
			)
		)
		(property "Author" "Antmicro"
			(at 330.2 189.23 0)
			(effects
				(font
					(size 1.27 1.27)
					(thickness 0.15)
				)
				(justify left bottom)
				(hide yes)
			)
		)
		(property "License" "Apache-2.0"
			(at 327.66 189.23 0)
			(effects
				(font
					(size 1.27 1.27)
					(thickness 0.15)
				)
				(justify left bottom)
				(hide yes)
			)
		)
		(property "VSD_class" "LED"
			(at 325.12 189.23 0)
			(effects
				(font
					(size 1.27 1.27)
				)
				(justify left bottom)
				(hide yes)
			)
		)
		(property "Color" "Green"
			(at 345.44 189.23 0)
			(effects
				(font
					(size 1.27 1.27)
				)
				(justify left bottom)
				(hide yes)
			)
		)
		(pin "1"
		)
		(pin "2"
		)
		(instances
			(project "gmsl-serializer"
				(path ""
					(reference "D11")
					(unit 1)
				)
			)
		)
	)
	(symbol
		(lib_id "antmicropower:GND")
		(at 311.15 135.89 0)
		(unit 1)
		(exclude_from_sim no)
		(in_bom yes)
		(on_board yes)
		(dnp no)
		(fields_autoplaced yes)
		(property "Reference" "#PWR0137"
			(at 320.04 138.43 0)
			(effects
				(font
					(size 1.27 1.27)
					(thickness 0.15)
				)
				(justify left bottom)
				(hide yes)
			)
		)
		(property "Value" "GND"
			(at 311.15 140.97 0)
			(effects
				(font
					(size 1.27 1.27)
					(thickness 0.15)
				)
			)
		)
		(property "Footprint" ""
			(at 320.04 143.51 0)
			(effects
				(font
					(size 1.27 1.27)
					(thickness 0.15)
				)
				(justify left bottom)
				(hide yes)
			)
		)
		(property "Datasheet" ""
			(at 320.04 148.59 0)
			(effects
				(font
					(size 1.27 1.27)
					(thickness 0.15)
				)
				(justify left bottom)
				(hide yes)
			)
		)
		(property "Description" ""
			(at 311.15 135.89 0)
			(effects
				(font
					(size 1.27 1.27)
				)
				(hide yes)
			)
		)
		(property "Author" "Antmicro"
			(at 320.04 143.51 0)
			(effects
				(font
					(size 1.27 1.27)
					(thickness 0.15)
				)
				(justify left bottom)
				(hide yes)
			)
		)
		(property "License" "Apache-2.0"
			(at 320.04 146.05 0)
			(effects
				(font
					(size 1.27 1.27)
					(thickness 0.15)
				)
				(justify left bottom)
				(hide yes)
			)
		)
		(pin "1"
		)
		(instances
			(project "gmsl-serializer"
				(path ""
					(reference "#PWR0137")
					(unit 1)
				)
			)
		)
	)
	(symbol
		(lib_id "antmicroPMICPowerDistributionSwitchesLoadDrivers:REF3012AIDBZT")
		(at 293.37 54.61 0)
		(unit 1)
		(exclude_from_sim no)
		(in_bom yes)
		(on_board yes)
		(dnp yes)
		(property "Reference" "U4"
			(at 302.26 48.26 0)
			(effects
				(font
					(size 1.27 1.27)
					(thickness 0.15)
				)
			)
		)
		(property "Value" "REF3012AIDBZT"
			(at 302.26 50.8 0)
			(effects
				(font
					(size 1.27 1.27)
					(thickness 0.15)
				)
			)
		)
		(property "Footprint" "antmicro-footprints:SOT-23-3"
			(at 326.39 64.77 0)
			(effects
				(font
					(size 1.27 1.27)
					(thickness 0.15)
				)
				(justify left bottom)
				(hide yes)
			)
		)
		(property "Datasheet" "https://www.ti.com/lit/gpn/REF3012"
			(at 326.39 67.31 0)
			(effects
				(font
					(size 1.27 1.27)
					(thickness 0.15)
				)
				(justify left bottom)
				(hide yes)
			)
		)
		(property "Description" ""
			(at 293.37 54.61 0)
			(effects
				(font
					(size 1.27 1.27)
				)
				(hide yes)
			)
		)
		(property "MPN" "REF3012AIDBZT"
			(at 326.39 69.85 0)
			(effects
				(font
					(size 1.27 1.27)
					(thickness 0.15)
				)
				(justify left bottom)
				(hide yes)
			)
		)
		(property "Manufacturer" "Texas Instruments"
			(at 326.39 72.39 0)
			(effects
				(font
					(size 1.27 1.27)
					(thickness 0.15)
				)
				(justify left bottom)
				(hide yes)
			)
		)
		(property "Author" "Antmicro"
			(at 326.39 74.93 0)
			(effects
				(font
					(size 1.27 1.27)
					(thickness 0.15)
				)
				(justify left bottom)
				(hide yes)
			)
		)
		(property "License" "Apache-2.0"
			(at 326.39 77.47 0)
			(effects
				(font
					(size 1.27 1.27)
					(thickness 0.15)
				)
				(justify left bottom)
				(hide yes)
			)
		)
		(pin "1"
		)
		(pin "2"
		)
		(pin "3"
		)
		(instances
			(project "gmsl-serializer"
				(path ""
					(reference "U4")
					(unit 1)
				)
			)
		)
	)
	(symbol
		(lib_id "antmicroCapacitors0402:C_220n_0402")
		(at 303.53 207.01 0)
		(unit 1)
		(exclude_from_sim no)
		(in_bom yes)
		(on_board yes)
		(dnp no)
		(property "Reference" "C21"
			(at 309.88 205.74 0)
			(effects
				(font
					(size 1.27 1.27)
					(thickness 0.15)
				)
			)
		)
		(property "Value" "C_220n_0402"
			(at 323.85 217.17 0)
			(effects
				(font
					(size 1.27 1.27)
					(thickness 0.15)
				)
				(justify left bottom)
				(hide yes)
			)
		)
		(property "Footprint" "antmicro-footprints:C_0402_1005Metric"
			(at 323.85 219.71 0)
			(effects
				(font
					(size 1.27 1.27)
					(thickness 0.15)
				)
				(justify left bottom)
				(hide yes)
			)
		)
		(property "Datasheet" "https://www.yageo.com/en/Chart/Download/pdf/CC0402KRX5R6BB224"
			(at 323.85 222.25 0)
			(effects
				(font
					(size 1.27 1.27)
					(thickness 0.15)
				)
				(justify left bottom)
				(hide yes)
			)
		)
		(property "Description" ""
			(at 303.53 207.01 0)
			(effects
				(font
					(size 1.27 1.27)
				)
				(hide yes)
			)
		)
		(property "MPN" "CC0402KRX5R6BB224"
			(at 323.85 224.79 0)
			(effects
				(font
					(size 1.27 1.27)
					(thickness 0.15)
				)
				(justify left bottom)
				(hide yes)
			)
		)
		(property "Manufacturer" "YAGEO"
			(at 323.85 227.33 0)
			(effects
				(font
					(size 1.27 1.27)
					(thickness 0.15)
				)
				(justify left bottom)
				(hide yes)
			)
		)
		(property "License" "Apache-2.0"
			(at 323.85 229.87 0)
			(effects
				(font
					(size 1.27 1.27)
					(thickness 0.15)
				)
				(justify left bottom)
				(hide yes)
			)
		)
		(property "Author" "Antmicro"
			(at 323.85 232.41 0)
			(effects
				(font
					(size 1.27 1.27)
					(thickness 0.15)
				)
				(justify left bottom)
				(hide yes)
			)
		)
		(property "Val" "220n"
			(at 311.15 208.28 0)
			(effects
				(font
					(size 1.27 1.27)
					(thickness 0.15)
				)
			)
		)
		(property "Voltage" ""
			(at 323.85 234.95 0)
			(effects
				(font
					(size 1.27 1.27)
				)
				(justify left bottom)
				(hide yes)
			)
		)
		(property "Dielectric" ""
			(at 323.85 237.49 0)
			(effects
				(font
					(size 1.27 1.27)
				)
				(justify left bottom)
				(hide yes)
			)
		)
		(pin "1"
		)
		(pin "2"
		)
		(instances
			(project "gmsl-serializer"
				(path ""
					(reference "C21")
					(unit 1)
				)
			)
		)
	)
	(symbol
		(lib_id "antmicroCapacitors0402:C_1u_16V_0402")
		(at 285.75 60.96 90)
		(unit 1)
		(exclude_from_sim no)
		(in_bom yes)
		(on_board yes)
		(dnp yes)
		(property "Reference" "C12"
			(at 275.59 57.15 90)
			(effects
				(font
					(size 1.27 1.27)
					(thickness 0.15)
				)
				(justify right)
			)
		)
		(property "Value" "C_1u_16V_0402"
			(at 295.91 40.64 0)
			(effects
				(font
					(size 1.27 1.27)
					(thickness 0.15)
				)
				(justify left bottom)
				(hide yes)
			)
		)
		(property "Footprint" "antmicro-footprints:C_0402_1005Metric"
			(at 298.45 40.64 0)
			(effects
				(font
					(size 1.27 1.27)
					(thickness 0.15)
				)
				(justify left bottom)
				(hide yes)
			)
		)
		(property "Datasheet" "https://www.kemet.com/en/us/capacitors/product/C0402C105M4PACTU.html"
			(at 300.99 40.64 0)
			(effects
				(font
					(size 1.27 1.27)
					(thickness 0.15)
				)
				(justify left bottom)
				(hide yes)
			)
		)
		(property "Description" ""
			(at 285.75 60.96 0)
			(effects
				(font
					(size 1.27 1.27)
				)
				(hide yes)
			)
		)
		(property "MPN" "C0402C105M4PACTU"
			(at 303.53 40.64 0)
			(effects
				(font
					(size 1.27 1.27)
					(thickness 0.15)
				)
				(justify left bottom)
				(hide yes)
			)
		)
		(property "Manufacturer" "KEMET"
			(at 306.07 40.64 0)
			(effects
				(font
					(size 1.27 1.27)
					(thickness 0.15)
				)
				(justify left bottom)
				(hide yes)
			)
		)
		(property "License" "Apache-2.0"
			(at 308.61 40.64 0)
			(effects
				(font
					(size 1.27 1.27)
					(thickness 0.15)
				)
				(justify left bottom)
				(hide yes)
			)
		)
		(property "Author" "Antmicro"
			(at 311.15 40.64 0)
			(effects
				(font
					(size 1.27 1.27)
					(thickness 0.15)
				)
				(justify left bottom)
				(hide yes)
			)
		)
		(property "Val" "1u"
			(at 275.59 59.69 90)
			(effects
				(font
					(size 1.27 1.27)
					(thickness 0.15)
				)
				(justify right)
			)
		)
		(property "Voltage" "16V"
			(at 313.69 40.64 0)
			(effects
				(font
					(size 1.27 1.27)
				)
				(justify left bottom)
				(hide yes)
			)
		)
		(property "Dielectric" ""
			(at 316.23 40.64 0)
			(effects
				(font
					(size 1.27 1.27)
				)
				(justify left bottom)
				(hide yes)
			)
		)
		(pin "1"
		)
		(pin "2"
		)
		(instances
			(project "gmsl-serializer"
				(path ""
					(reference "C12")
					(unit 1)
				)
			)
		)
	)
	(symbol
		(lib_id "antmicroDCDCConverters:AP62301_TSOT")
		(at 78.74 204.47 0)
		(unit 1)
		(exclude_from_sim no)
		(in_bom yes)
		(on_board yes)
		(dnp no)
		(fields_autoplaced yes)
		(property "Reference" "U2"
			(at 88.9 196.215 0)
			(effects
				(font
					(size 1.27 1.27)
					(thickness 0.15)
				)
			)
		)
		(property "Value" "AP62301_TSOT"
			(at 114.3 212.09 0)
			(effects
				(font
					(size 1.27 1.27)
					(thickness 0.15)
				)
				(justify left bottom)
				(hide yes)
			)
		)
		(property "Footprint" "antmicro-footprints:TSOT23-6"
			(at 114.3 214.63 0)
			(effects
				(font
					(size 1.27 1.27)
					(thickness 0.15)
				)
				(justify left bottom)
				(hide yes)
			)
		)
		(property "Datasheet" "https://www.diodes.com/assets/Datasheets/AP62300_AP62301_AP62300T.pdf"
			(at 114.3 217.17 0)
			(effects
				(font
					(size 1.27 1.27)
					(thickness 0.15)
				)
				(justify left bottom)
				(hide yes)
			)
		)
		(property "Description" ""
			(at 78.74 204.47 0)
			(effects
				(font
					(size 1.27 1.27)
				)
				(hide yes)
			)
		)
		(property "MPN" "AP62301WU-7"
			(at 88.9 198.755 0)
			(effects
				(font
					(size 1.27 1.27)
					(thickness 0.15)
				)
			)
		)
		(property "Manufacturer" "Diodes Incorporated"
			(at 114.3 219.71 0)
			(effects
				(font
					(size 1.27 1.27)
					(thickness 0.15)
				)
				(justify left bottom)
				(hide yes)
			)
		)
		(property "Author" "Antmicro"
			(at 114.3 222.25 0)
			(effects
				(font
					(size 1.27 1.27)
					(thickness 0.15)
				)
				(justify left bottom)
				(hide yes)
			)
		)
		(property "License" "Apache-2.0"
			(at 114.3 224.79 0)
			(effects
				(font
					(size 1.27 1.27)
					(thickness 0.15)
				)
				(justify left bottom)
				(hide yes)
			)
		)
		(pin "1"
		)
		(pin "2"
		)
		(pin "3"
		)
		(pin "4"
		)
		(pin "5"
		)
		(pin "6"
		)
		(instances
			(project "gmsl-serializer"
				(path ""
					(reference "U2")
					(unit 1)
				)
			)
		)
	)
	(symbol
		(lib_id "antmicropower:GND")
		(at 55.88 217.17 0)
		(unit 1)
		(exclude_from_sim no)
		(in_bom yes)
		(on_board yes)
		(dnp no)
		(property "Reference" "#PWR0109"
			(at 64.77 219.71 0)
			(effects
				(font
					(size 1.27 1.27)
					(thickness 0.15)
				)
				(justify left bottom)
				(hide yes)
			)
		)
		(property "Value" "GND"
			(at 55.88 220.98 0)
			(effects
				(font
					(size 1.27 1.27)
					(thickness 0.15)
				)
			)
		)
		(property "Footprint" ""
			(at 64.77 224.79 0)
			(effects
				(font
					(size 1.27 1.27)
					(thickness 0.15)
				)
				(justify left bottom)
				(hide yes)
			)
		)
		(property "Datasheet" ""
			(at 64.77 229.87 0)
			(effects
				(font
					(size 1.27 1.27)
					(thickness 0.15)
				)
				(justify left bottom)
				(hide yes)
			)
		)
		(property "Description" ""
			(at 55.88 217.17 0)
			(effects
				(font
					(size 1.27 1.27)
				)
				(hide yes)
			)
		)
		(property "Author" "Antmicro"
			(at 64.77 224.79 0)
			(effects
				(font
					(size 1.27 1.27)
					(thickness 0.15)
				)
				(justify left bottom)
				(hide yes)
			)
		)
		(property "License" "Apache-2.0"
			(at 64.77 227.33 0)
			(effects
				(font
					(size 1.27 1.27)
					(thickness 0.15)
				)
				(justify left bottom)
				(hide yes)
			)
		)
		(pin "1"
		)
		(instances
			(project "gmsl-serializer"
				(path ""
					(reference "#PWR0109")
					(unit 1)
				)
			)
		)
	)
	(symbol
		(lib_id "antmicropower:+12V")
		(at 87.63 72.39 0)
		(unit 1)
		(exclude_from_sim no)
		(in_bom yes)
		(on_board yes)
		(dnp no)
		(fields_autoplaced yes)
		(property "Reference" "#PWR0127"
			(at 87.63 76.2 0)
			(effects
				(font
					(size 1.27 1.27)
				)
				(hide yes)
			)
		)
		(property "Value" "+12V"
			(at 87.63 67.31 0)
			(effects
				(font
					(size 1.27 1.27)
				)
			)
		)
		(property "Footprint" ""
			(at 87.63 72.39 0)
			(effects
				(font
					(size 1.27 1.27)
				)
				(hide yes)
			)
		)
		(property "Datasheet" ""
			(at 87.63 72.39 0)
			(effects
				(font
					(size 1.27 1.27)
				)
				(hide yes)
			)
		)
		(property "Description" ""
			(at 87.63 72.39 0)
			(effects
				(font
					(size 1.27 1.27)
				)
				(hide yes)
			)
		)
		(pin "1"
		)
		(instances
			(project "gmsl-serializer"
				(path ""
					(reference "#PWR0127")
					(unit 1)
				)
			)
		)
	)
	(symbol
		(lib_id "antmicroCapacitors0603:C_10u_25V_0603")
		(at 261.62 210.82 90)
		(unit 1)
		(exclude_from_sim no)
		(in_bom yes)
		(on_board yes)
		(dnp no)
		(property "Reference" "C19"
			(at 262.89 205.74 90)
			(effects
				(font
					(size 1.27 1.27)
					(thickness 0.15)
				)
				(justify right)
			)
		)
		(property "Value" "C_10u_25V_0603"
			(at 271.78 190.5 0)
			(effects
				(font
					(size 1.27 1.27)
					(thickness 0.15)
				)
				(justify left bottom)
				(hide yes)
			)
		)
		(property "Footprint" "antmicro-footprints:C_0603_1608Metric"
			(at 274.32 190.5 0)
			(effects
				(font
					(size 1.27 1.27)
					(thickness 0.15)
				)
				(justify left bottom)
				(hide yes)
			)
		)
		(property "Datasheet" "https://product.tdk.com/en/search/capacitor/ceramic/mlcc/info?part_no=C1608X5R1E106M080AC"
			(at 276.86 190.5 0)
			(effects
				(font
					(size 1.27 1.27)
					(thickness 0.15)
				)
				(justify left bottom)
				(hide yes)
			)
		)
		(property "Description" ""
			(at 261.62 210.82 0)
			(effects
				(font
					(size 1.27 1.27)
				)
				(hide yes)
			)
		)
		(property "MPN" "C1608X5R1E106M080AC"
			(at 279.4 190.5 0)
			(effects
				(font
					(size 1.27 1.27)
					(thickness 0.15)
				)
				(justify left bottom)
				(hide yes)
			)
		)
		(property "Manufacturer" "TDK"
			(at 281.94 190.5 0)
			(effects
				(font
					(size 1.27 1.27)
					(thickness 0.15)
				)
				(justify left bottom)
				(hide yes)
			)
		)
		(property "License" "Apache-2.0"
			(at 284.48 190.5 0)
			(effects
				(font
					(size 1.27 1.27)
					(thickness 0.15)
				)
				(justify left bottom)
				(hide yes)
			)
		)
		(property "Author" "Antmicro"
			(at 287.02 190.5 0)
			(effects
				(font
					(size 1.27 1.27)
					(thickness 0.15)
				)
				(justify left bottom)
				(hide yes)
			)
		)
		(property "Val" "10u"
			(at 262.89 210.185 90)
			(effects
				(font
					(size 1.27 1.27)
					(thickness 0.15)
				)
				(justify right)
			)
		)
		(property "Voltage" "25V"
			(at 289.56 190.5 0)
			(effects
				(font
					(size 1.27 1.27)
				)
				(justify left bottom)
				(hide yes)
			)
		)
		(property "Dielectric" ""
			(at 292.1 190.5 0)
			(effects
				(font
					(size 1.27 1.27)
				)
				(justify left bottom)
				(hide yes)
			)
		)
		(pin "1"
		)
		(pin "2"
		)
		(instances
			(project "gmsl-serializer"
				(path ""
					(reference "C19")
					(unit 1)
				)
			)
		)
	)
	(symbol
		(lib_id "antmicroTestPoints:TP_1.5mm_SMD")
		(at 167.64 81.28 0)
		(unit 1)
		(exclude_from_sim no)
		(in_bom no)
		(on_board yes)
		(dnp no)
		(property "Reference" "TP1"
			(at 171.45 76.2 0)
			(effects
				(font
					(size 1.27 1.27)
					(thickness 0.15)
				)
				(justify right)
			)
		)
		(property "Value" "TP_1.5mm_SMD"
			(at 182.88 88.9 0)
			(effects
				(font
					(size 1.27 1.27)
					(thickness 0.15)
				)
				(justify left bottom)
				(hide yes)
			)
		)
		(property "Footprint" "antmicro-footprints:TP_SMD_1.5mm"
			(at 182.88 91.44 0)
			(effects
				(font
					(size 1.27 1.27)
					(thickness 0.15)
				)
				(justify left bottom)
				(hide yes)
			)
		)
		(property "Datasheet" ""
			(at 185.42 93.98 0)
			(effects
				(font
					(size 1.27 1.27)
					(thickness 0.15)
				)
				(justify left bottom)
				(hide yes)
			)
		)
		(property "Description" ""
			(at 167.64 81.28 0)
			(effects
				(font
					(size 1.27 1.27)
				)
				(hide yes)
			)
		)
		(property "MPN" ""
			(at 167.64 81.28 0)
			(effects
				(font
					(size 1.27 1.27)
				)
				(hide yes)
			)
		)
		(property "Manufacturer" ""
			(at 167.64 81.28 0)
			(effects
				(font
					(size 1.27 1.27)
				)
				(hide yes)
			)
		)
		(property "Author" "Antmicro"
			(at 182.88 96.52 0)
			(effects
				(font
					(size 1.27 1.27)
					(thickness 0.15)
				)
				(justify left bottom)
				(hide yes)
			)
		)
		(property "License" "Apache-2.0"
			(at 182.88 99.06 0)
			(effects
				(font
					(size 1.27 1.27)
					(thickness 0.15)
				)
				(justify left bottom)
				(hide yes)
			)
		)
		(pin "1"
		)
		(instances
			(project "gmsl-serializer"
				(path ""
					(reference "TP1")
					(unit 1)
				)
			)
		)
	)
	(symbol
		(lib_id "antmicropower:GND")
		(at 273.05 214.63 0)
		(unit 1)
		(exclude_from_sim no)
		(in_bom yes)
		(on_board yes)
		(dnp no)
		(property "Reference" "#PWR024"
			(at 281.94 217.17 0)
			(effects
				(font
					(size 1.27 1.27)
					(thickness 0.15)
				)
				(justify left bottom)
				(hide yes)
			)
		)
		(property "Value" "GND"
			(at 273.05 218.44 0)
			(effects
				(font
					(size 1.27 1.27)
					(thickness 0.15)
				)
			)
		)
		(property "Footprint" ""
			(at 281.94 222.25 0)
			(effects
				(font
					(size 1.27 1.27)
					(thickness 0.15)
				)
				(justify left bottom)
				(hide yes)
			)
		)
		(property "Datasheet" ""
			(at 281.94 227.33 0)
			(effects
				(font
					(size 1.27 1.27)
					(thickness 0.15)
				)
				(justify left bottom)
				(hide yes)
			)
		)
		(property "Description" ""
			(at 273.05 214.63 0)
			(effects
				(font
					(size 1.27 1.27)
				)
				(hide yes)
			)
		)
		(property "Author" "Antmicro"
			(at 281.94 222.25 0)
			(effects
				(font
					(size 1.27 1.27)
					(thickness 0.15)
				)
				(justify left bottom)
				(hide yes)
			)
		)
		(property "License" "Apache-2.0"
			(at 281.94 224.79 0)
			(effects
				(font
					(size 1.27 1.27)
					(thickness 0.15)
				)
				(justify left bottom)
				(hide yes)
			)
		)
		(pin "1"
		)
		(instances
			(project "gmsl-serializer"
				(path ""
					(reference "#PWR024")
					(unit 1)
				)
			)
		)
	)
	(symbol
		(lib_id "antmicropower:+1V8")
		(at 270.51 124.46 0)
		(unit 1)
		(exclude_from_sim no)
		(in_bom yes)
		(on_board yes)
		(dnp no)
		(property "Reference" "#PWR0133"
			(at 285.75 127 0)
			(effects
				(font
					(size 1.27 1.27)
					(thickness 0.15)
				)
				(justify left bottom)
				(hide yes)
			)
		)
		(property "Value" "+1V8"
			(at 270.51 120.65 0)
			(effects
				(font
					(size 1.27 1.27)
					(thickness 0.15)
				)
			)
		)
		(property "Footprint" ""
			(at 285.75 132.08 0)
			(effects
				(font
					(size 1.27 1.27)
					(thickness 0.15)
				)
				(justify left bottom)
				(hide yes)
			)
		)
		(property "Datasheet" ""
			(at 285.75 134.62 0)
			(effects
				(font
					(size 1.27 1.27)
					(thickness 0.15)
				)
				(justify left bottom)
				(hide yes)
			)
		)
		(property "Description" ""
			(at 270.51 124.46 0)
			(effects
				(font
					(size 1.27 1.27)
				)
				(hide yes)
			)
		)
		(property "Author" "Antmicro"
			(at 285.75 132.08 0)
			(effects
				(font
					(size 1.27 1.27)
					(thickness 0.15)
				)
				(justify left bottom)
				(hide yes)
			)
		)
		(property "License" "Apache-2.0"
			(at 285.75 134.62 0)
			(effects
				(font
					(size 1.27 1.27)
					(thickness 0.15)
				)
				(justify left bottom)
				(hide yes)
			)
		)
		(pin "1"
		)
		(instances
			(project "gmsl-serializer"
				(path ""
					(reference "#PWR0133")
					(unit 1)
				)
			)
		)
	)
	(symbol
		(lib_id "antmicropower:+5V")
		(at 285.75 52.07 0)
		(unit 1)
		(exclude_from_sim no)
		(in_bom yes)
		(on_board yes)
		(dnp no)
		(fields_autoplaced yes)
		(property "Reference" "#PWR0116"
			(at 300.99 54.61 0)
			(effects
				(font
					(size 1.27 1.27)
					(thickness 0.15)
				)
				(justify left bottom)
				(hide yes)
			)
		)
		(property "Value" "+5V"
			(at 285.75 46.355 0)
			(effects
				(font
					(size 1.27 1.27)
					(thickness 0.15)
				)
			)
		)
		(property "Footprint" ""
			(at 300.99 59.69 0)
			(effects
				(font
					(size 1.27 1.27)
					(thickness 0.15)
				)
				(justify left bottom)
				(hide yes)
			)
		)
		(property "Datasheet" ""
			(at 300.99 62.23 0)
			(effects
				(font
					(size 1.27 1.27)
					(thickness 0.15)
				)
				(justify left bottom)
				(hide yes)
			)
		)
		(property "Description" ""
			(at 285.75 52.07 0)
			(effects
				(font
					(size 1.27 1.27)
				)
				(hide yes)
			)
		)
		(property "Author" "Antmicro"
			(at 300.99 59.69 0)
			(effects
				(font
					(size 1.27 1.27)
					(thickness 0.15)
				)
				(justify left bottom)
				(hide yes)
			)
		)
		(property "License" "Apache-2.0"
			(at 300.99 62.23 0)
			(effects
				(font
					(size 1.27 1.27)
					(thickness 0.15)
				)
				(justify left bottom)
				(hide yes)
			)
		)
		(pin "1"
		)
		(instances
			(project "gmsl-serializer"
				(path ""
					(reference "#PWR0116")
					(unit 1)
				)
			)
		)
	)
	(symbol
		(lib_id "antmicroResistors0402:R_470R_0402")
		(at 165.1 97.79 90)
		(unit 1)
		(exclude_from_sim no)
		(in_bom yes)
		(on_board yes)
		(dnp no)
		(fields_autoplaced yes)
		(property "Reference" "R15"
			(at 167.64 93.9799 90)
			(effects
				(font
					(size 1.27 1.27)
					(thickness 0.15)
				)
				(justify right)
			)
		)
		(property "Value" "R_470R_0402"
			(at 177.8 77.47 0)
			(effects
				(font
					(size 1.27 1.27)
					(thickness 0.15)
				)
				(justify left bottom)
				(hide yes)
			)
		)
		(property "Footprint" "antmicro-footprints:R_0402_1005Metric"
			(at 180.34 77.47 0)
			(effects
				(font
					(size 1.27 1.27)
					(thickness 0.15)
				)
				(justify left bottom)
				(hide yes)
			)
		)
		(property "Datasheet" "https://www.bourns.com/docs/product-datasheets/cr.pdf"
			(at 182.88 77.47 0)
			(effects
				(font
					(size 1.27 1.27)
					(thickness 0.15)
				)
				(justify left bottom)
				(hide yes)
			)
		)
		(property "Description" ""
			(at 165.1 97.79 0)
			(effects
				(font
					(size 1.27 1.27)
				)
				(hide yes)
			)
		)
		(property "MPN" "CR0402-FX-4700GLF"
			(at 185.42 77.47 0)
			(effects
				(font
					(size 1.27 1.27)
					(thickness 0.15)
				)
				(justify left bottom)
				(hide yes)
			)
		)
		(property "Manufacturer" "Bourns"
			(at 187.96 77.47 0)
			(effects
				(font
					(size 1.27 1.27)
					(thickness 0.15)
				)
				(justify left bottom)
				(hide yes)
			)
		)
		(property "License" "Apache-2.0"
			(at 190.5 77.47 0)
			(effects
				(font
					(size 1.27 1.27)
					(thickness 0.15)
				)
				(justify left bottom)
				(hide yes)
			)
		)
		(property "Author" "Antmicro"
			(at 193.04 77.47 0)
			(effects
				(font
					(size 1.27 1.27)
					(thickness 0.15)
				)
				(justify left bottom)
				(hide yes)
			)
		)
		(property "Val" "470R"
			(at 167.64 96.5199 90)
			(effects
				(font
					(size 1.27 1.27)
					(thickness 0.15)
				)
				(justify right)
			)
		)
		(property "Tolerance" "1%"
			(at 175.26 77.47 0)
			(effects
				(font
					(size 1.27 1.27)
				)
				(justify left bottom)
				(hide yes)
			)
		)
		(pin "1"
		)
		(pin "2"
		)
		(instances
			(project "gmsl-serializer"
				(path ""
					(reference "R15")
					(unit 1)
				)
			)
		)
	)
	(symbol
		(lib_id "antmicropower:+1V2")
		(at 311.15 124.46 0)
		(unit 1)
		(exclude_from_sim no)
		(in_bom yes)
		(on_board yes)
		(dnp no)
		(property "Reference" "#PWR0136"
			(at 311.15 128.27 0)
			(effects
				(font
					(size 1.27 1.27)
				)
				(hide yes)
			)
		)
		(property "Value" "+1V2"
			(at 311.15 120.65 0)
			(effects
				(font
					(size 1.27 1.27)
				)
			)
		)
		(property "Footprint" ""
			(at 311.15 124.46 0)
			(effects
				(font
					(size 1.27 1.27)
				)
				(hide yes)
			)
		)
		(property "Datasheet" ""
			(at 311.15 124.46 0)
			(effects
				(font
					(size 1.27 1.27)
				)
				(hide yes)
			)
		)
		(property "Description" ""
			(at 311.15 124.46 0)
			(effects
				(font
					(size 1.27 1.27)
				)
				(hide yes)
			)
		)
		(pin "1"
		)
		(instances
			(project "gmsl-serializer"
				(path ""
					(reference "#PWR0136")
					(unit 1)
				)
			)
		)
	)
	(symbol
		(lib_id "antmicropower:+12V")
		(at 54.61 78.74 0)
		(unit 1)
		(exclude_from_sim no)
		(in_bom yes)
		(on_board yes)
		(dnp no)
		(fields_autoplaced yes)
		(property "Reference" "#PWR0126"
			(at 54.61 82.55 0)
			(effects
				(font
					(size 1.27 1.27)
				)
				(hide yes)
			)
		)
		(property "Value" "+12V"
			(at 54.61 73.66 0)
			(effects
				(font
					(size 1.27 1.27)
				)
			)
		)
		(property "Footprint" ""
			(at 54.61 78.74 0)
			(effects
				(font
					(size 1.27 1.27)
				)
				(hide yes)
			)
		)
		(property "Datasheet" ""
			(at 54.61 78.74 0)
			(effects
				(font
					(size 1.27 1.27)
				)
				(hide yes)
			)
		)
		(property "Description" ""
			(at 54.61 78.74 0)
			(effects
				(font
					(size 1.27 1.27)
				)
				(hide yes)
			)
		)
		(pin "1"
		)
		(instances
			(project "gmsl-serializer"
				(path ""
					(reference "#PWR0126")
					(unit 1)
				)
			)
		)
	)
	(symbol
		(lib_id "antmicropower:GND")
		(at 135.89 223.52 0)
		(unit 1)
		(exclude_from_sim no)
		(in_bom yes)
		(on_board yes)
		(dnp no)
		(property "Reference" "#PWR0111"
			(at 144.78 226.06 0)
			(effects
				(font
					(size 1.27 1.27)
					(thickness 0.15)
				)
				(justify left bottom)
				(hide yes)
			)
		)
		(property "Value" "GND"
			(at 135.89 227.33 0)
			(effects
				(font
					(size 1.27 1.27)
					(thickness 0.15)
				)
			)
		)
		(property "Footprint" ""
			(at 144.78 231.14 0)
			(effects
				(font
					(size 1.27 1.27)
					(thickness 0.15)
				)
				(justify left bottom)
				(hide yes)
			)
		)
		(property "Datasheet" ""
			(at 144.78 236.22 0)
			(effects
				(font
					(size 1.27 1.27)
					(thickness 0.15)
				)
				(justify left bottom)
				(hide yes)
			)
		)
		(property "Description" ""
			(at 135.89 223.52 0)
			(effects
				(font
					(size 1.27 1.27)
				)
				(hide yes)
			)
		)
		(property "Author" "Antmicro"
			(at 144.78 231.14 0)
			(effects
				(font
					(size 1.27 1.27)
					(thickness 0.15)
				)
				(justify left bottom)
				(hide yes)
			)
		)
		(property "License" "Apache-2.0"
			(at 144.78 233.68 0)
			(effects
				(font
					(size 1.27 1.27)
					(thickness 0.15)
				)
				(justify left bottom)
				(hide yes)
			)
		)
		(pin "1"
		)
		(instances
			(project "gmsl-serializer"
				(path ""
					(reference "#PWR0111")
					(unit 1)
				)
			)
		)
	)
	(symbol
		(lib_id "antmicroTestPoints:TP_1.5mm_SMD")
		(at 304.8 125.73 90)
		(unit 1)
		(exclude_from_sim no)
		(in_bom no)
		(on_board yes)
		(dnp no)
		(property "Reference" "TP5"
			(at 303.53 120.65 90)
			(effects
				(font
					(size 1.27 1.27)
					(thickness 0.15)
				)
				(justify right)
			)
		)
		(property "Value" "TP_1.5mm_SMD"
			(at 312.42 110.49 0)
			(effects
				(font
					(size 1.27 1.27)
					(thickness 0.15)
				)
				(justify left bottom)
				(hide yes)
			)
		)
		(property "Footprint" "antmicro-footprints:TP_SMD_1.5mm"
			(at 314.96 110.49 0)
			(effects
				(font
					(size 1.27 1.27)
					(thickness 0.15)
				)
				(justify left bottom)
				(hide yes)
			)
		)
		(property "Datasheet" ""
			(at 317.5 107.95 0)
			(effects
				(font
					(size 1.27 1.27)
					(thickness 0.15)
				)
				(justify left bottom)
				(hide yes)
			)
		)
		(property "Description" ""
			(at 304.8 125.73 0)
			(effects
				(font
					(size 1.27 1.27)
				)
				(hide yes)
			)
		)
		(property "MPN" ""
			(at 304.8 125.73 0)
			(effects
				(font
					(size 1.27 1.27)
				)
				(hide yes)
			)
		)
		(property "Manufacturer" ""
			(at 304.8 125.73 0)
			(effects
				(font
					(size 1.27 1.27)
				)
				(hide yes)
			)
		)
		(property "Author" "Antmicro"
			(at 320.04 110.49 0)
			(effects
				(font
					(size 1.27 1.27)
					(thickness 0.15)
				)
				(justify left bottom)
				(hide yes)
			)
		)
		(property "License" "Apache-2.0"
			(at 322.58 110.49 0)
			(effects
				(font
					(size 1.27 1.27)
					(thickness 0.15)
				)
				(justify left bottom)
				(hide yes)
			)
		)
		(pin "1"
		)
		(instances
			(project "gmsl-serializer"
				(path ""
					(reference "TP5")
					(unit 1)
				)
			)
		)
	)
	(symbol
		(lib_id "antmicroCapacitors0402:C_22u_0402")
		(at 330.2 218.44 90)
		(unit 1)
		(exclude_from_sim no)
		(in_bom yes)
		(on_board yes)
		(dnp no)
		(property "Reference" "C34"
			(at 332.74 214.63 90)
			(effects
				(font
					(size 1.27 1.27)
					(thickness 0.15)
				)
				(justify right)
			)
		)
		(property "Value" "C_22u_0402"
			(at 340.36 198.12 0)
			(effects
				(font
					(size 1.27 1.27)
					(thickness 0.15)
				)
				(justify left bottom)
				(hide yes)
			)
		)
		(property "Footprint" "antmicro-footprints:C_0402_1005Metric"
			(at 342.9 198.12 0)
			(effects
				(font
					(size 1.27 1.27)
					(thickness 0.15)
				)
				(justify left bottom)
				(hide yes)
			)
		)
		(property "Datasheet" "https://www.murata.com/products/productdetail?partno=GRM158R60J226ME01%23"
			(at 345.44 198.12 0)
			(effects
				(font
					(size 1.27 1.27)
					(thickness 0.15)
				)
				(justify left bottom)
				(hide yes)
			)
		)
		(property "Description" ""
			(at 330.2 218.44 0)
			(effects
				(font
					(size 1.27 1.27)
				)
				(hide yes)
			)
		)
		(property "MPN" "GRM158R60J226ME01D"
			(at 347.98 198.12 0)
			(effects
				(font
					(size 1.27 1.27)
					(thickness 0.15)
				)
				(justify left bottom)
				(hide yes)
			)
		)
		(property "Manufacturer" "Murata"
			(at 350.52 198.12 0)
			(effects
				(font
					(size 1.27 1.27)
					(thickness 0.15)
				)
				(justify left bottom)
				(hide yes)
			)
		)
		(property "License" "Apache-2.0"
			(at 353.06 198.12 0)
			(effects
				(font
					(size 1.27 1.27)
					(thickness 0.15)
				)
				(justify left bottom)
				(hide yes)
			)
		)
		(property "Author" "Antmicro"
			(at 355.6 198.12 0)
			(effects
				(font
					(size 1.27 1.27)
					(thickness 0.15)
				)
				(justify left bottom)
				(hide yes)
			)
		)
		(property "Val" "22u"
			(at 332.74 217.17 90)
			(effects
				(font
					(size 1.27 1.27)
					(thickness 0.15)
				)
				(justify right)
			)
		)
		(property "Voltage" ""
			(at 358.14 198.12 0)
			(effects
				(font
					(size 1.27 1.27)
				)
				(justify left bottom)
				(hide yes)
			)
		)
		(property "Dielectric" ""
			(at 360.68 198.12 0)
			(effects
				(font
					(size 1.27 1.27)
				)
				(justify left bottom)
				(hide yes)
			)
		)
		(pin "1"
		)
		(pin "2"
		)
		(instances
			(project "gmsl-serializer"
				(path ""
					(reference "C34")
					(unit 1)
				)
			)
		)
	)
	(symbol
		(lib_id "antmicroTestPoints:TP_1.5mm_SMD")
		(at 194.31 85.09 90)
		(unit 1)
		(exclude_from_sim no)
		(in_bom no)
		(on_board yes)
		(dnp no)
		(property "Reference" "TP9"
			(at 193.04 80.01 90)
			(effects
				(font
					(size 1.27 1.27)
					(thickness 0.15)
				)
				(justify right)
			)
		)
		(property "Value" "TP_1.5mm_SMD"
			(at 201.93 69.85 0)
			(effects
				(font
					(size 1.27 1.27)
					(thickness 0.15)
				)
				(justify left bottom)
				(hide yes)
			)
		)
		(property "Footprint" "antmicro-footprints:TP_SMD_1.5mm"
			(at 204.47 69.85 0)
			(effects
				(font
					(size 1.27 1.27)
					(thickness 0.15)
				)
				(justify left bottom)
				(hide yes)
			)
		)
		(property "Datasheet" ""
			(at 207.01 67.31 0)
			(effects
				(font
					(size 1.27 1.27)
					(thickness 0.15)
				)
				(justify left bottom)
				(hide yes)
			)
		)
		(property "Description" ""
			(at 194.31 85.09 0)
			(effects
				(font
					(size 1.27 1.27)
				)
				(hide yes)
			)
		)
		(property "MPN" ""
			(at 194.31 85.09 0)
			(effects
				(font
					(size 1.27 1.27)
				)
				(hide yes)
			)
		)
		(property "Manufacturer" ""
			(at 194.31 85.09 0)
			(effects
				(font
					(size 1.27 1.27)
				)
				(hide yes)
			)
		)
		(property "Author" "Antmicro"
			(at 209.55 69.85 0)
			(effects
				(font
					(size 1.27 1.27)
					(thickness 0.15)
				)
				(justify left bottom)
				(hide yes)
			)
		)
		(property "License" "Apache-2.0"
			(at 212.09 69.85 0)
			(effects
				(font
					(size 1.27 1.27)
					(thickness 0.15)
				)
				(justify left bottom)
				(hide yes)
			)
		)
		(pin "1"
		)
		(instances
			(project "gmsl-serializer"
				(path ""
					(reference "TP9")
					(unit 1)
				)
			)
		)
	)
	(symbol
		(lib_id "antmicroResistors0402:R_10k_0402")
		(at 273.05 213.36 90)
		(unit 1)
		(exclude_from_sim no)
		(in_bom yes)
		(on_board yes)
		(dnp no)
		(fields_autoplaced yes)
		(property "Reference" "R42"
			(at 274.955 209.5499 90)
			(effects
				(font
					(size 1.27 1.27)
					(thickness 0.15)
				)
				(justify right)
			)
		)
		(property "Value" "R_10k_0402"
			(at 285.75 193.04 0)
			(effects
				(font
					(size 1.27 1.27)
					(thickness 0.15)
				)
				(justify left bottom)
				(hide yes)
			)
		)
		(property "Footprint" "antmicro-footprints:R_0402_1005Metric"
			(at 288.29 193.04 0)
			(effects
				(font
					(size 1.27 1.27)
					(thickness 0.15)
				)
				(justify left bottom)
				(hide yes)
			)
		)
		(property "Datasheet" "https://www.bourns.com/docs/product-datasheets/cr.pdf"
			(at 290.83 193.04 0)
			(effects
				(font
					(size 1.27 1.27)
					(thickness 0.15)
				)
				(justify left bottom)
				(hide yes)
			)
		)
		(property "Description" ""
			(at 273.05 213.36 0)
			(effects
				(font
					(size 1.27 1.27)
				)
				(hide yes)
			)
		)
		(property "MPN" "CR0402-FX-1002GLF"
			(at 293.37 193.04 0)
			(effects
				(font
					(size 1.27 1.27)
					(thickness 0.15)
				)
				(justify left bottom)
				(hide yes)
			)
		)
		(property "Manufacturer" "Bourns"
			(at 295.91 193.04 0)
			(effects
				(font
					(size 1.27 1.27)
					(thickness 0.15)
				)
				(justify left bottom)
				(hide yes)
			)
		)
		(property "License" "Apache-2.0"
			(at 298.45 193.04 0)
			(effects
				(font
					(size 1.27 1.27)
					(thickness 0.15)
				)
				(justify left bottom)
				(hide yes)
			)
		)
		(property "Author" "Antmicro"
			(at 300.99 193.04 0)
			(effects
				(font
					(size 1.27 1.27)
					(thickness 0.15)
				)
				(justify left bottom)
				(hide yes)
			)
		)
		(property "Val" "10k"
			(at 274.955 212.0899 90)
			(effects
				(font
					(size 1.27 1.27)
					(thickness 0.15)
				)
				(justify right)
			)
		)
		(property "Tolerance" "1%"
			(at 283.21 193.04 0)
			(effects
				(font
					(size 1.27 1.27)
				)
				(justify left bottom)
				(hide yes)
			)
		)
		(pin "1"
		)
		(pin "2"
		)
		(instances
			(project "gmsl-serializer"
				(path ""
					(reference "R42")
					(unit 1)
				)
			)
		)
	)
	(symbol
		(lib_id "antmicropower:+5V")
		(at 351.79 106.68 0)
		(unit 1)
		(exclude_from_sim no)
		(in_bom yes)
		(on_board yes)
		(dnp no)
		(property "Reference" "#PWR05"
			(at 367.03 109.22 0)
			(effects
				(font
					(size 1.27 1.27)
					(thickness 0.15)
				)
				(justify left bottom)
				(hide yes)
			)
		)
		(property "Value" "+5V"
			(at 351.79 102.87 0)
			(effects
				(font
					(size 1.27 1.27)
					(thickness 0.15)
				)
			)
		)
		(property "Footprint" ""
			(at 367.03 114.3 0)
			(effects
				(font
					(size 1.27 1.27)
					(thickness 0.15)
				)
				(justify left bottom)
				(hide yes)
			)
		)
		(property "Datasheet" ""
			(at 367.03 116.84 0)
			(effects
				(font
					(size 1.27 1.27)
					(thickness 0.15)
				)
				(justify left bottom)
				(hide yes)
			)
		)
		(property "Description" ""
			(at 351.79 106.68 0)
			(effects
				(font
					(size 1.27 1.27)
				)
				(hide yes)
			)
		)
		(property "Author" "Antmicro"
			(at 367.03 114.3 0)
			(effects
				(font
					(size 1.27 1.27)
					(thickness 0.15)
				)
				(justify left bottom)
				(hide yes)
			)
		)
		(property "License" "Apache-2.0"
			(at 367.03 116.84 0)
			(effects
				(font
					(size 1.27 1.27)
					(thickness 0.15)
				)
				(justify left bottom)
				(hide yes)
			)
		)
		(pin "1"
		)
		(instances
			(project "gmsl-serializer"
				(path ""
					(reference "#PWR05")
					(unit 1)
				)
			)
		)
	)
	(symbol
		(lib_id "antmicroResistors0402:R_10k_0402")
		(at 87.63 92.71 90)
		(unit 1)
		(exclude_from_sim no)
		(in_bom yes)
		(on_board yes)
		(dnp no)
		(fields_autoplaced yes)
		(property "Reference" "R27"
			(at 89.535 88.8999 90)
			(effects
				(font
					(size 1.27 1.27)
					(thickness 0.15)
				)
				(justify right)
			)
		)
		(property "Value" "R_10k_0402"
			(at 100.33 72.39 0)
			(effects
				(font
					(size 1.27 1.27)
					(thickness 0.15)
				)
				(justify left bottom)
				(hide yes)
			)
		)
		(property "Footprint" "antmicro-footprints:R_0402_1005Metric"
			(at 102.87 72.39 0)
			(effects
				(font
					(size 1.27 1.27)
					(thickness 0.15)
				)
				(justify left bottom)
				(hide yes)
			)
		)
		(property "Datasheet" "https://www.bourns.com/docs/product-datasheets/cr.pdf"
			(at 105.41 72.39 0)
			(effects
				(font
					(size 1.27 1.27)
					(thickness 0.15)
				)
				(justify left bottom)
				(hide yes)
			)
		)
		(property "Description" ""
			(at 87.63 92.71 0)
			(effects
				(font
					(size 1.27 1.27)
				)
				(hide yes)
			)
		)
		(property "MPN" "CR0402-FX-1002GLF"
			(at 107.95 72.39 0)
			(effects
				(font
					(size 1.27 1.27)
					(thickness 0.15)
				)
				(justify left bottom)
				(hide yes)
			)
		)
		(property "Manufacturer" "Bourns"
			(at 110.49 72.39 0)
			(effects
				(font
					(size 1.27 1.27)
					(thickness 0.15)
				)
				(justify left bottom)
				(hide yes)
			)
		)
		(property "License" "Apache-2.0"
			(at 113.03 72.39 0)
			(effects
				(font
					(size 1.27 1.27)
					(thickness 0.15)
				)
				(justify left bottom)
				(hide yes)
			)
		)
		(property "Author" "Antmicro"
			(at 115.57 72.39 0)
			(effects
				(font
					(size 1.27 1.27)
					(thickness 0.15)
				)
				(justify left bottom)
				(hide yes)
			)
		)
		(property "Val" "10k"
			(at 89.535 91.4399 90)
			(effects
				(font
					(size 1.27 1.27)
					(thickness 0.15)
				)
				(justify right)
			)
		)
		(property "Tolerance" "1%"
			(at 97.79 72.39 0)
			(effects
				(font
					(size 1.27 1.27)
				)
				(justify left bottom)
				(hide yes)
			)
		)
		(pin "1"
		)
		(pin "2"
		)
		(instances
			(project "gmsl-serializer"
				(path ""
					(reference "R27")
					(unit 1)
				)
			)
		)
	)
	(symbol
		(lib_id "antmicropower:+1V8")
		(at 157.48 203.2 0)
		(unit 1)
		(exclude_from_sim no)
		(in_bom yes)
		(on_board yes)
		(dnp no)
		(property "Reference" "#PWR0107"
			(at 172.72 205.74 0)
			(effects
				(font
					(size 1.27 1.27)
					(thickness 0.15)
				)
				(justify left bottom)
				(hide yes)
			)
		)
		(property "Value" "+1V8"
			(at 157.48 199.39 0)
			(effects
				(font
					(size 1.27 1.27)
					(thickness 0.15)
				)
			)
		)
		(property "Footprint" ""
			(at 172.72 210.82 0)
			(effects
				(font
					(size 1.27 1.27)
					(thickness 0.15)
				)
				(justify left bottom)
				(hide yes)
			)
		)
		(property "Datasheet" ""
			(at 172.72 213.36 0)
			(effects
				(font
					(size 1.27 1.27)
					(thickness 0.15)
				)
				(justify left bottom)
				(hide yes)
			)
		)
		(property "Description" ""
			(at 157.48 203.2 0)
			(effects
				(font
					(size 1.27 1.27)
				)
				(hide yes)
			)
		)
		(property "Author" "Antmicro"
			(at 172.72 210.82 0)
			(effects
				(font
					(size 1.27 1.27)
					(thickness 0.15)
				)
				(justify left bottom)
				(hide yes)
			)
		)
		(property "License" "Apache-2.0"
			(at 172.72 213.36 0)
			(effects
				(font
					(size 1.27 1.27)
					(thickness 0.15)
				)
				(justify left bottom)
				(hide yes)
			)
		)
		(pin "1"
		)
		(instances
			(project "gmsl-serializer"
				(path ""
					(reference "#PWR0107")
					(unit 1)
				)
			)
		)
	)
	(symbol
		(lib_id "antmicropower:GND")
		(at 194.31 86.36 0)
		(unit 1)
		(exclude_from_sim no)
		(in_bom yes)
		(on_board yes)
		(dnp no)
		(property "Reference" "#PWR015"
			(at 203.2 88.9 0)
			(effects
				(font
					(size 1.27 1.27)
					(thickness 0.15)
				)
				(justify left bottom)
				(hide yes)
			)
		)
		(property "Value" "GND"
			(at 194.31 90.17 0)
			(effects
				(font
					(size 1.27 1.27)
					(thickness 0.15)
				)
			)
		)
		(property "Footprint" ""
			(at 203.2 93.98 0)
			(effects
				(font
					(size 1.27 1.27)
					(thickness 0.15)
				)
				(justify left bottom)
				(hide yes)
			)
		)
		(property "Datasheet" ""
			(at 203.2 99.06 0)
			(effects
				(font
					(size 1.27 1.27)
					(thickness 0.15)
				)
				(justify left bottom)
				(hide yes)
			)
		)
		(property "Description" ""
			(at 194.31 86.36 0)
			(effects
				(font
					(size 1.27 1.27)
				)
				(hide yes)
			)
		)
		(property "Author" "Antmicro"
			(at 203.2 93.98 0)
			(effects
				(font
					(size 1.27 1.27)
					(thickness 0.15)
				)
				(justify left bottom)
				(hide yes)
			)
		)
		(property "License" "Apache-2.0"
			(at 203.2 96.52 0)
			(effects
				(font
					(size 1.27 1.27)
					(thickness 0.15)
				)
				(justify left bottom)
				(hide yes)
			)
		)
		(pin "1"
		)
		(instances
			(project "gmsl-serializer"
				(path ""
					(reference "#PWR015")
					(unit 1)
				)
			)
		)
	)
	(symbol
		(lib_id "antmicropower:GND")
		(at 144.78 99.06 0)
		(unit 1)
		(exclude_from_sim no)
		(in_bom yes)
		(on_board yes)
		(dnp no)
		(property "Reference" "#PWR0131"
			(at 153.67 101.6 0)
			(effects
				(font
					(size 1.27 1.27)
					(thickness 0.15)
				)
				(justify left bottom)
				(hide yes)
			)
		)
		(property "Value" "GND"
			(at 144.78 102.87 0)
			(effects
				(font
					(size 1.27 1.27)
					(thickness 0.15)
				)
			)
		)
		(property "Footprint" ""
			(at 153.67 106.68 0)
			(effects
				(font
					(size 1.27 1.27)
					(thickness 0.15)
				)
				(justify left bottom)
				(hide yes)
			)
		)
		(property "Datasheet" ""
			(at 153.67 111.76 0)
			(effects
				(font
					(size 1.27 1.27)
					(thickness 0.15)
				)
				(justify left bottom)
				(hide yes)
			)
		)
		(property "Description" ""
			(at 144.78 99.06 0)
			(effects
				(font
					(size 1.27 1.27)
				)
				(hide yes)
			)
		)
		(property "Author" "Antmicro"
			(at 153.67 106.68 0)
			(effects
				(font
					(size 1.27 1.27)
					(thickness 0.15)
				)
				(justify left bottom)
				(hide yes)
			)
		)
		(property "License" "Apache-2.0"
			(at 153.67 109.22 0)
			(effects
				(font
					(size 1.27 1.27)
					(thickness 0.15)
				)
				(justify left bottom)
				(hide yes)
			)
		)
		(pin "1"
		)
		(instances
			(project "gmsl-serializer"
				(path ""
					(reference "#PWR0131")
					(unit 1)
				)
			)
		)
	)
	(symbol
		(lib_id "antmicropower:GND")
		(at 285.75 62.23 0)
		(unit 1)
		(exclude_from_sim no)
		(in_bom yes)
		(on_board yes)
		(dnp no)
		(property "Reference" "#PWR010"
			(at 294.64 64.77 0)
			(effects
				(font
					(size 1.27 1.27)
					(thickness 0.15)
				)
				(justify left bottom)
				(hide yes)
			)
		)
		(property "Value" "GND"
			(at 285.75 66.04 0)
			(effects
				(font
					(size 1.27 1.27)
					(thickness 0.15)
				)
			)
		)
		(property "Footprint" ""
			(at 294.64 69.85 0)
			(effects
				(font
					(size 1.27 1.27)
					(thickness 0.15)
				)
				(justify left bottom)
				(hide yes)
			)
		)
		(property "Datasheet" ""
			(at 294.64 74.93 0)
			(effects
				(font
					(size 1.27 1.27)
					(thickness 0.15)
				)
				(justify left bottom)
				(hide yes)
			)
		)
		(property "Description" ""
			(at 285.75 62.23 0)
			(effects
				(font
					(size 1.27 1.27)
				)
				(hide yes)
			)
		)
		(property "Author" "Antmicro"
			(at 294.64 69.85 0)
			(effects
				(font
					(size 1.27 1.27)
					(thickness 0.15)
				)
				(justify left bottom)
				(hide yes)
			)
		)
		(property "License" "Apache-2.0"
			(at 294.64 72.39 0)
			(effects
				(font
					(size 1.27 1.27)
					(thickness 0.15)
				)
				(justify left bottom)
				(hide yes)
			)
		)
		(pin "1"
		)
		(instances
			(project "gmsl-serializer"
				(path ""
					(reference "#PWR010")
					(unit 1)
				)
			)
		)
	)
	(symbol
		(lib_id "antmicropower:+1V8")
		(at 158.75 226.06 0)
		(unit 1)
		(exclude_from_sim no)
		(in_bom yes)
		(on_board yes)
		(dnp no)
		(property "Reference" "#PWR012"
			(at 173.99 228.6 0)
			(effects
				(font
					(size 1.27 1.27)
					(thickness 0.15)
				)
				(justify left bottom)
				(hide yes)
			)
		)
		(property "Value" "+1V8"
			(at 158.75 222.25 0)
			(effects
				(font
					(size 1.27 1.27)
					(thickness 0.15)
				)
			)
		)
		(property "Footprint" ""
			(at 173.99 233.68 0)
			(effects
				(font
					(size 1.27 1.27)
					(thickness 0.15)
				)
				(justify left bottom)
				(hide yes)
			)
		)
		(property "Datasheet" ""
			(at 173.99 236.22 0)
			(effects
				(font
					(size 1.27 1.27)
					(thickness 0.15)
				)
				(justify left bottom)
				(hide yes)
			)
		)
		(property "Description" ""
			(at 158.75 226.06 0)
			(effects
				(font
					(size 1.27 1.27)
				)
				(hide yes)
			)
		)
		(property "Author" "Antmicro"
			(at 173.99 233.68 0)
			(effects
				(font
					(size 1.27 1.27)
					(thickness 0.15)
				)
				(justify left bottom)
				(hide yes)
			)
		)
		(property "License" "Apache-2.0"
			(at 173.99 236.22 0)
			(effects
				(font
					(size 1.27 1.27)
					(thickness 0.15)
				)
				(justify left bottom)
				(hide yes)
			)
		)
		(pin "1"
		)
		(instances
			(project "gmsl-serializer"
				(path ""
					(reference "#PWR012")
					(unit 1)
				)
			)
		)
	)
	(symbol
		(lib_id "antmicroDCDCConverters:AP62301_TSOT")
		(at 281.94 201.93 0)
		(unit 1)
		(exclude_from_sim no)
		(in_bom yes)
		(on_board yes)
		(dnp no)
		(fields_autoplaced yes)
		(property "Reference" "U3"
			(at 292.1 194.31 0)
			(effects
				(font
					(size 1.27 1.27)
					(thickness 0.15)
				)
			)
		)
		(property "Value" "AP62301_TSOT"
			(at 317.5 209.55 0)
			(effects
				(font
					(size 1.27 1.27)
					(thickness 0.15)
				)
				(justify left bottom)
				(hide yes)
			)
		)
		(property "Footprint" "antmicro-footprints:TSOT23-6"
			(at 317.5 212.09 0)
			(effects
				(font
					(size 1.27 1.27)
					(thickness 0.15)
				)
				(justify left bottom)
				(hide yes)
			)
		)
		(property "Datasheet" "https://www.diodes.com/assets/Datasheets/AP62300_AP62301_AP62300T.pdf"
			(at 317.5 214.63 0)
			(effects
				(font
					(size 1.27 1.27)
					(thickness 0.15)
				)
				(justify left bottom)
				(hide yes)
			)
		)
		(property "Description" ""
			(at 281.94 201.93 0)
			(effects
				(font
					(size 1.27 1.27)
				)
				(hide yes)
			)
		)
		(property "MPN" "AP62301WU-7"
			(at 292.1 196.85 0)
			(effects
				(font
					(size 1.27 1.27)
					(thickness 0.15)
				)
			)
		)
		(property "Manufacturer" "Diodes Incorporated"
			(at 317.5 217.17 0)
			(effects
				(font
					(size 1.27 1.27)
					(thickness 0.15)
				)
				(justify left bottom)
				(hide yes)
			)
		)
		(property "Author" "Antmicro"
			(at 317.5 219.71 0)
			(effects
				(font
					(size 1.27 1.27)
					(thickness 0.15)
				)
				(justify left bottom)
				(hide yes)
			)
		)
		(property "License" "Apache-2.0"
			(at 317.5 222.25 0)
			(effects
				(font
					(size 1.27 1.27)
					(thickness 0.15)
				)
				(justify left bottom)
				(hide yes)
			)
		)
		(pin "1"
		)
		(pin "2"
		)
		(pin "3"
		)
		(pin "4"
		)
		(pin "5"
		)
		(pin "6"
		)
		(instances
			(project "gmsl-serializer"
				(path ""
					(reference "U3")
					(unit 1)
				)
			)
		)
	)
	(symbol
		(lib_id "antmicroResistors0402:R_100k_0402")
		(at 339.09 137.16 90)
		(unit 1)
		(exclude_from_sim no)
		(in_bom yes)
		(on_board yes)
		(dnp no)
		(fields_autoplaced yes)
		(property "Reference" "R34"
			(at 341.63 133.3499 90)
			(effects
				(font
					(size 1.27 1.27)
					(thickness 0.15)
				)
				(justify right)
			)
		)
		(property "Value" "R_100k_0402"
			(at 351.79 116.84 0)
			(effects
				(font
					(size 1.27 1.27)
					(thickness 0.15)
				)
				(justify left bottom)
				(hide yes)
			)
		)
		(property "Footprint" "antmicro-footprints:R_0402_1005Metric"
			(at 354.33 116.84 0)
			(effects
				(font
					(size 1.27 1.27)
					(thickness 0.15)
				)
				(justify left bottom)
				(hide yes)
			)
		)
		(property "Datasheet" "https://www.bourns.com/docs/product-datasheets/cr.pdf"
			(at 356.87 116.84 0)
			(effects
				(font
					(size 1.27 1.27)
					(thickness 0.15)
				)
				(justify left bottom)
				(hide yes)
			)
		)
		(property "Description" ""
			(at 339.09 137.16 0)
			(effects
				(font
					(size 1.27 1.27)
				)
				(hide yes)
			)
		)
		(property "MPN" "CR0402-FX-1003GLF"
			(at 359.41 116.84 0)
			(effects
				(font
					(size 1.27 1.27)
					(thickness 0.15)
				)
				(justify left bottom)
				(hide yes)
			)
		)
		(property "Manufacturer" "Bourns"
			(at 361.95 116.84 0)
			(effects
				(font
					(size 1.27 1.27)
					(thickness 0.15)
				)
				(justify left bottom)
				(hide yes)
			)
		)
		(property "License" "Apache-2.0"
			(at 364.49 116.84 0)
			(effects
				(font
					(size 1.27 1.27)
					(thickness 0.15)
				)
				(justify left bottom)
				(hide yes)
			)
		)
		(property "Author" "Antmicro"
			(at 367.03 116.84 0)
			(effects
				(font
					(size 1.27 1.27)
					(thickness 0.15)
				)
				(justify left bottom)
				(hide yes)
			)
		)
		(property "Val" "100k"
			(at 341.63 135.8899 90)
			(effects
				(font
					(size 1.27 1.27)
					(thickness 0.15)
				)
				(justify right)
			)
		)
		(property "Tolerance" "1%"
			(at 349.25 116.84 0)
			(effects
				(font
					(size 1.27 1.27)
				)
				(justify left bottom)
				(hide yes)
			)
		)
		(pin "1"
		)
		(pin "2"
		)
		(instances
			(project "gmsl-serializer"
				(path ""
					(reference "R34")
					(unit 1)
				)
			)
		)
	)
	(symbol
		(lib_id "antmicroResistors0402:R_10k_0402")
		(at 71.12 200.66 90)
		(unit 1)
		(exclude_from_sim no)
		(in_bom yes)
		(on_board yes)
		(dnp no)
		(fields_autoplaced yes)
		(property "Reference" "R8"
			(at 73.025 196.8499 90)
			(effects
				(font
					(size 1.27 1.27)
					(thickness 0.15)
				)
				(justify right)
			)
		)
		(property "Value" "R_10k_0402"
			(at 83.82 180.34 0)
			(effects
				(font
					(size 1.27 1.27)
					(thickness 0.15)
				)
				(justify left bottom)
				(hide yes)
			)
		)
		(property "Footprint" "antmicro-footprints:R_0402_1005Metric"
			(at 86.36 180.34 0)
			(effects
				(font
					(size 1.27 1.27)
					(thickness 0.15)
				)
				(justify left bottom)
				(hide yes)
			)
		)
		(property "Datasheet" "https://www.bourns.com/docs/product-datasheets/cr.pdf"
			(at 88.9 180.34 0)
			(effects
				(font
					(size 1.27 1.27)
					(thickness 0.15)
				)
				(justify left bottom)
				(hide yes)
			)
		)
		(property "Description" ""
			(at 71.12 200.66 0)
			(effects
				(font
					(size 1.27 1.27)
				)
				(hide yes)
			)
		)
		(property "MPN" "CR0402-FX-1002GLF"
			(at 91.44 180.34 0)
			(effects
				(font
					(size 1.27 1.27)
					(thickness 0.15)
				)
				(justify left bottom)
				(hide yes)
			)
		)
		(property "Manufacturer" "Bourns"
			(at 93.98 180.34 0)
			(effects
				(font
					(size 1.27 1.27)
					(thickness 0.15)
				)
				(justify left bottom)
				(hide yes)
			)
		)
		(property "License" "Apache-2.0"
			(at 96.52 180.34 0)
			(effects
				(font
					(size 1.27 1.27)
					(thickness 0.15)
				)
				(justify left bottom)
				(hide yes)
			)
		)
		(property "Author" "Antmicro"
			(at 99.06 180.34 0)
			(effects
				(font
					(size 1.27 1.27)
					(thickness 0.15)
				)
				(justify left bottom)
				(hide yes)
			)
		)
		(property "Val" "10k"
			(at 73.025 199.3899 90)
			(effects
				(font
					(size 1.27 1.27)
					(thickness 0.15)
				)
				(justify right)
			)
		)
		(property "Tolerance" "1%"
			(at 81.28 180.34 0)
			(effects
				(font
					(size 1.27 1.27)
				)
				(justify left bottom)
				(hide yes)
			)
		)
		(pin "1"
		)
		(pin "2"
		)
		(instances
			(project "gmsl-serializer"
				(path ""
					(reference "R8")
					(unit 1)
				)
			)
		)
	)
	(symbol
		(lib_id "antmicropower:GND")
		(at 87.63 93.98 0)
		(unit 1)
		(exclude_from_sim no)
		(in_bom yes)
		(on_board yes)
		(dnp no)
		(property "Reference" "#PWR09"
			(at 96.52 96.52 0)
			(effects
				(font
					(size 1.27 1.27)
					(thickness 0.15)
				)
				(justify left bottom)
				(hide yes)
			)
		)
		(property "Value" "GND"
			(at 87.63 97.79 0)
			(effects
				(font
					(size 1.27 1.27)
					(thickness 0.15)
				)
			)
		)
		(property "Footprint" ""
			(at 96.52 101.6 0)
			(effects
				(font
					(size 1.27 1.27)
					(thickness 0.15)
				)
				(justify left bottom)
				(hide yes)
			)
		)
		(property "Datasheet" ""
			(at 96.52 106.68 0)
			(effects
				(font
					(size 1.27 1.27)
					(thickness 0.15)
				)
				(justify left bottom)
				(hide yes)
			)
		)
		(property "Description" ""
			(at 87.63 93.98 0)
			(effects
				(font
					(size 1.27 1.27)
				)
				(hide yes)
			)
		)
		(property "Author" "Antmicro"
			(at 96.52 101.6 0)
			(effects
				(font
					(size 1.27 1.27)
					(thickness 0.15)
				)
				(justify left bottom)
				(hide yes)
			)
		)
		(property "License" "Apache-2.0"
			(at 96.52 104.14 0)
			(effects
				(font
					(size 1.27 1.27)
					(thickness 0.15)
				)
				(justify left bottom)
				(hide yes)
			)
		)
		(pin "1"
		)
		(instances
			(project "gmsl-serializer"
				(path ""
					(reference "#PWR09")
					(unit 1)
				)
			)
		)
	)
	(symbol
		(lib_id "antmicropower:PWR_FLAG")
		(at 76.2 80.01 0)
		(unit 1)
		(exclude_from_sim no)
		(in_bom yes)
		(on_board yes)
		(dnp no)
		(property "Reference" "#FLG0103"
			(at 76.2 78.105 0)
			(effects
				(font
					(size 1.27 1.27)
				)
				(hide yes)
			)
		)
		(property "Value" "PWR_FLAG"
			(at 76.2 76.2 0)
			(effects
				(font
					(size 1.27 1.27)
				)
			)
		)
		(property "Footprint" ""
			(at 76.2 80.01 0)
			(effects
				(font
					(size 1.27 1.27)
				)
				(hide yes)
			)
		)
		(property "Datasheet" ""
			(at 76.2 80.01 0)
			(effects
				(font
					(size 1.27 1.27)
				)
				(hide yes)
			)
		)
		(property "Description" ""
			(at 76.2 80.01 0)
			(effects
				(font
					(size 1.27 1.27)
				)
				(hide yes)
			)
		)
		(pin "1"
		)
		(instances
			(project "gmsl-serializer"
				(path ""
					(reference "#FLG0103")
					(unit 1)
				)
			)
		)
	)
	(symbol
		(lib_id "antmicroResistors0402:R_200R_0402")
		(at 350.52 218.44 270)
		(mirror x)
		(unit 1)
		(exclude_from_sim no)
		(in_bom yes)
		(on_board yes)
		(dnp no)
		(property "Reference" "R46"
			(at 353.06 214.63 90)
			(effects
				(font
					(size 1.27 1.27)
					(thickness 0.15)
				)
				(justify left)
			)
		)
		(property "Value" "R_200R_0402"
			(at 337.82 198.12 0)
			(effects
				(font
					(size 1.27 1.27)
					(thickness 0.15)
				)
				(justify left bottom)
				(hide yes)
			)
		)
		(property "Footprint" "antmicro-footprints:R_0402_1005Metric"
			(at 335.28 198.12 0)
			(effects
				(font
					(size 1.27 1.27)
					(thickness 0.15)
				)
				(justify left bottom)
				(hide yes)
			)
		)
		(property "Datasheet" "https://www.bourns.com/docs/product-datasheets/cr.pdf"
			(at 332.74 198.12 0)
			(effects
				(font
					(size 1.27 1.27)
					(thickness 0.15)
				)
				(justify left bottom)
				(hide yes)
			)
		)
		(property "Description" ""
			(at 350.52 218.44 0)
			(effects
				(font
					(size 1.27 1.27)
				)
				(hide yes)
			)
		)
		(property "MPN" "CR0402-FX-2000GLF"
			(at 330.2 198.12 0)
			(effects
				(font
					(size 1.27 1.27)
					(thickness 0.15)
				)
				(justify left bottom)
				(hide yes)
			)
		)
		(property "Manufacturer" "Bourns"
			(at 327.66 198.12 0)
			(effects
				(font
					(size 1.27 1.27)
					(thickness 0.15)
				)
				(justify left bottom)
				(hide yes)
			)
		)
		(property "License" "Apache-2.0"
			(at 325.12 198.12 0)
			(effects
				(font
					(size 1.27 1.27)
					(thickness 0.15)
				)
				(justify left bottom)
				(hide yes)
			)
		)
		(property "Author" "Antmicro"
			(at 322.58 198.12 0)
			(effects
				(font
					(size 1.27 1.27)
					(thickness 0.15)
				)
				(justify left bottom)
				(hide yes)
			)
		)
		(property "Val" "200R"
			(at 353.06 217.17 90)
			(effects
				(font
					(size 1.27 1.27)
					(thickness 0.15)
				)
				(justify left)
			)
		)
		(property "Tolerance" "1%"
			(at 340.36 198.12 0)
			(effects
				(font
					(size 1.27 1.27)
				)
				(justify left bottom)
				(hide yes)
			)
		)
		(property "Public" ""
			(at 320.04 198.12 0)
			(effects
				(font
					(size 1.27 1.27)
				)
				(justify left bottom)
				(hide yes)
			)
		)
		(pin "2"
		)
		(pin "1"
		)
		(instances
			(project "gmsl-serializer"
				(path ""
					(reference "R46")
					(unit 1)
				)
			)
		)
	)
	(symbol
		(lib_id "antmicroResistors0402:R_470R_0402")
		(at 171.45 209.55 90)
		(unit 1)
		(exclude_from_sim no)
		(in_bom yes)
		(on_board yes)
		(dnp no)
		(fields_autoplaced yes)
		(property "Reference" "R39"
			(at 173.99 205.7399 90)
			(effects
				(font
					(size 1.27 1.27)
					(thickness 0.15)
				)
				(justify right)
			)
		)
		(property "Value" "R_470R_0402"
			(at 184.15 189.23 0)
			(effects
				(font
					(size 1.27 1.27)
					(thickness 0.15)
				)
				(justify left bottom)
				(hide yes)
			)
		)
		(property "Footprint" "antmicro-footprints:R_0402_1005Metric"
			(at 186.69 189.23 0)
			(effects
				(font
					(size 1.27 1.27)
					(thickness 0.15)
				)
				(justify left bottom)
				(hide yes)
			)
		)
		(property "Datasheet" "https://www.bourns.com/docs/product-datasheets/cr.pdf"
			(at 189.23 189.23 0)
			(effects
				(font
					(size 1.27 1.27)
					(thickness 0.15)
				)
				(justify left bottom)
				(hide yes)
			)
		)
		(property "Description" ""
			(at 171.45 209.55 0)
			(effects
				(font
					(size 1.27 1.27)
				)
				(hide yes)
			)
		)
		(property "MPN" "CR0402-FX-4700GLF"
			(at 191.77 189.23 0)
			(effects
				(font
					(size 1.27 1.27)
					(thickness 0.15)
				)
				(justify left bottom)
				(hide yes)
			)
		)
		(property "Manufacturer" "Bourns"
			(at 194.31 189.23 0)
			(effects
				(font
					(size 1.27 1.27)
					(thickness 0.15)
				)
				(justify left bottom)
				(hide yes)
			)
		)
		(property "License" "Apache-2.0"
			(at 196.85 189.23 0)
			(effects
				(font
					(size 1.27 1.27)
					(thickness 0.15)
				)
				(justify left bottom)
				(hide yes)
			)
		)
		(property "Author" "Antmicro"
			(at 199.39 189.23 0)
			(effects
				(font
					(size 1.27 1.27)
					(thickness 0.15)
				)
				(justify left bottom)
				(hide yes)
			)
		)
		(property "Val" "470R"
			(at 173.99 208.2799 90)
			(effects
				(font
					(size 1.27 1.27)
					(thickness 0.15)
				)
				(justify right)
			)
		)
		(property "Tolerance" "1%"
			(at 181.61 189.23 0)
			(effects
				(font
					(size 1.27 1.27)
				)
				(justify left bottom)
				(hide yes)
			)
		)
		(pin "1"
		)
		(pin "2"
		)
		(instances
			(project "gmsl-serializer"
				(path ""
					(reference "R39")
					(unit 1)
				)
			)
		)
	)
	(symbol
		(lib_id "antmicropower:PWR_FLAG")
		(at 317.5 53.34 0)
		(unit 1)
		(exclude_from_sim no)
		(in_bom yes)
		(on_board yes)
		(dnp no)
		(property "Reference" "#FLG02"
			(at 317.5 51.435 0)
			(effects
				(font
					(size 1.27 1.27)
				)
				(hide yes)
			)
		)
		(property "Value" "PWR_FLAG"
			(at 317.5 49.53 0)
			(effects
				(font
					(size 1.27 1.27)
				)
			)
		)
		(property "Footprint" ""
			(at 317.5 53.34 0)
			(effects
				(font
					(size 1.27 1.27)
				)
				(hide yes)
			)
		)
		(property "Datasheet" ""
			(at 317.5 53.34 0)
			(effects
				(font
					(size 1.27 1.27)
				)
				(hide yes)
			)
		)
		(property "Description" ""
			(at 317.5 53.34 0)
			(effects
				(font
					(size 1.27 1.27)
				)
				(hide yes)
			)
		)
		(pin "1"
		)
		(instances
			(project "gmsl-serializer"
				(path ""
					(reference "#FLG02")
					(unit 1)
				)
			)
		)
	)
	(symbol
		(lib_id "antmicropower:GND")
		(at 71.12 217.17 0)
		(unit 1)
		(exclude_from_sim no)
		(in_bom yes)
		(on_board yes)
		(dnp no)
		(property "Reference" "#PWR08"
			(at 80.01 219.71 0)
			(effects
				(font
					(size 1.27 1.27)
					(thickness 0.15)
				)
				(justify left bottom)
				(hide yes)
			)
		)
		(property "Value" "GND"
			(at 71.12 220.98 0)
			(effects
				(font
					(size 1.27 1.27)
					(thickness 0.15)
				)
			)
		)
		(property "Footprint" ""
			(at 80.01 224.79 0)
			(effects
				(font
					(size 1.27 1.27)
					(thickness 0.15)
				)
				(justify left bottom)
				(hide yes)
			)
		)
		(property "Datasheet" ""
			(at 80.01 229.87 0)
			(effects
				(font
					(size 1.27 1.27)
					(thickness 0.15)
				)
				(justify left bottom)
				(hide yes)
			)
		)
		(property "Description" ""
			(at 71.12 217.17 0)
			(effects
				(font
					(size 1.27 1.27)
				)
				(hide yes)
			)
		)
		(property "Author" "Antmicro"
			(at 80.01 224.79 0)
			(effects
				(font
					(size 1.27 1.27)
					(thickness 0.15)
				)
				(justify left bottom)
				(hide yes)
			)
		)
		(property "License" "Apache-2.0"
			(at 80.01 227.33 0)
			(effects
				(font
					(size 1.27 1.27)
					(thickness 0.15)
				)
				(justify left bottom)
				(hide yes)
			)
		)
		(pin "1"
		)
		(instances
			(project "gmsl-serializer"
				(path ""
					(reference "#PWR08")
					(unit 1)
				)
			)
		)
	)
	(symbol
		(lib_id "antmicroResistors0402:R_10k_0402")
		(at 135.89 97.79 90)
		(unit 1)
		(exclude_from_sim no)
		(in_bom yes)
		(on_board yes)
		(dnp no)
		(fields_autoplaced yes)
		(property "Reference" "R10"
			(at 137.795 93.9799 90)
			(effects
				(font
					(size 1.27 1.27)
					(thickness 0.15)
				)
				(justify right)
			)
		)
		(property "Value" "R_10k_0402"
			(at 148.59 77.47 0)
			(effects
				(font
					(size 1.27 1.27)
					(thickness 0.15)
				)
				(justify left bottom)
				(hide yes)
			)
		)
		(property "Footprint" "antmicro-footprints:R_0402_1005Metric"
			(at 151.13 77.47 0)
			(effects
				(font
					(size 1.27 1.27)
					(thickness 0.15)
				)
				(justify left bottom)
				(hide yes)
			)
		)
		(property "Datasheet" "https://www.bourns.com/docs/product-datasheets/cr.pdf"
			(at 153.67 77.47 0)
			(effects
				(font
					(size 1.27 1.27)
					(thickness 0.15)
				)
				(justify left bottom)
				(hide yes)
			)
		)
		(property "Description" ""
			(at 135.89 97.79 0)
			(effects
				(font
					(size 1.27 1.27)
				)
				(hide yes)
			)
		)
		(property "MPN" "CR0402-FX-1002GLF"
			(at 156.21 77.47 0)
			(effects
				(font
					(size 1.27 1.27)
					(thickness 0.15)
				)
				(justify left bottom)
				(hide yes)
			)
		)
		(property "Manufacturer" "Bourns"
			(at 158.75 77.47 0)
			(effects
				(font
					(size 1.27 1.27)
					(thickness 0.15)
				)
				(justify left bottom)
				(hide yes)
			)
		)
		(property "License" "Apache-2.0"
			(at 161.29 77.47 0)
			(effects
				(font
					(size 1.27 1.27)
					(thickness 0.15)
				)
				(justify left bottom)
				(hide yes)
			)
		)
		(property "Author" "Antmicro"
			(at 163.83 77.47 0)
			(effects
				(font
					(size 1.27 1.27)
					(thickness 0.15)
				)
				(justify left bottom)
				(hide yes)
			)
		)
		(property "Val" "10k"
			(at 137.795 96.5199 90)
			(effects
				(font
					(size 1.27 1.27)
					(thickness 0.15)
				)
				(justify right)
			)
		)
		(property "Tolerance" "1%"
			(at 146.05 77.47 0)
			(effects
				(font
					(size 1.27 1.27)
				)
				(justify left bottom)
				(hide yes)
			)
		)
		(pin "1"
		)
		(pin "2"
		)
		(instances
			(project "gmsl-serializer"
				(path ""
					(reference "R10")
					(unit 1)
				)
			)
		)
	)
	(symbol
		(lib_id "antmicropower:PWR_FLAG")
		(at 148.59 203.2 0)
		(unit 1)
		(exclude_from_sim no)
		(in_bom yes)
		(on_board yes)
		(dnp no)
		(property "Reference" "#FLG0102"
			(at 148.59 201.295 0)
			(effects
				(font
					(size 1.27 1.27)
				)
				(hide yes)
			)
		)
		(property "Value" "PWR_FLAG"
			(at 148.59 199.39 0)
			(effects
				(font
					(size 1.27 1.27)
				)
			)
		)
		(property "Footprint" ""
			(at 148.59 203.2 0)
			(effects
				(font
					(size 1.27 1.27)
				)
				(hide yes)
			)
		)
		(property "Datasheet" ""
			(at 148.59 203.2 0)
			(effects
				(font
					(size 1.27 1.27)
				)
				(hide yes)
			)
		)
		(property "Description" ""
			(at 148.59 203.2 0)
			(effects
				(font
					(size 1.27 1.27)
				)
				(hide yes)
			)
		)
		(pin "1"
		)
		(instances
			(project "gmsl-serializer"
				(path ""
					(reference "#FLG0102")
					(unit 1)
				)
			)
		)
	)
	(symbol
		(lib_id "antmicroCapacitors0402:C_22u_0402")
		(at 127 222.25 90)
		(unit 1)
		(exclude_from_sim no)
		(in_bom yes)
		(on_board yes)
		(dnp no)
		(property "Reference" "C6"
			(at 129.54 218.44 90)
			(effects
				(font
					(size 1.27 1.27)
					(thickness 0.15)
				)
				(justify right)
			)
		)
		(property "Value" "C_22u_0402"
			(at 137.16 201.93 0)
			(effects
				(font
					(size 1.27 1.27)
					(thickness 0.15)
				)
				(justify left bottom)
				(hide yes)
			)
		)
		(property "Footprint" "antmicro-footprints:C_0402_1005Metric"
			(at 139.7 201.93 0)
			(effects
				(font
					(size 1.27 1.27)
					(thickness 0.15)
				)
				(justify left bottom)
				(hide yes)
			)
		)
		(property "Datasheet" "https://www.murata.com/products/productdetail?partno=GRM158R60J226ME01%23"
			(at 142.24 201.93 0)
			(effects
				(font
					(size 1.27 1.27)
					(thickness 0.15)
				)
				(justify left bottom)
				(hide yes)
			)
		)
		(property "Description" ""
			(at 127 222.25 0)
			(effects
				(font
					(size 1.27 1.27)
				)
				(hide yes)
			)
		)
		(property "MPN" "GRM158R60J226ME01D"
			(at 144.78 201.93 0)
			(effects
				(font
					(size 1.27 1.27)
					(thickness 0.15)
				)
				(justify left bottom)
				(hide yes)
			)
		)
		(property "Manufacturer" "Murata"
			(at 147.32 201.93 0)
			(effects
				(font
					(size 1.27 1.27)
					(thickness 0.15)
				)
				(justify left bottom)
				(hide yes)
			)
		)
		(property "License" "Apache-2.0"
			(at 149.86 201.93 0)
			(effects
				(font
					(size 1.27 1.27)
					(thickness 0.15)
				)
				(justify left bottom)
				(hide yes)
			)
		)
		(property "Author" "Antmicro"
			(at 152.4 201.93 0)
			(effects
				(font
					(size 1.27 1.27)
					(thickness 0.15)
				)
				(justify left bottom)
				(hide yes)
			)
		)
		(property "Val" "22u"
			(at 129.54 220.98 90)
			(effects
				(font
					(size 1.27 1.27)
					(thickness 0.15)
				)
				(justify right)
			)
		)
		(property "Voltage" ""
			(at 154.94 201.93 0)
			(effects
				(font
					(size 1.27 1.27)
				)
				(justify left bottom)
				(hide yes)
			)
		)
		(property "Dielectric" ""
			(at 157.48 201.93 0)
			(effects
				(font
					(size 1.27 1.27)
				)
				(justify left bottom)
				(hide yes)
			)
		)
		(pin "1"
		)
		(pin "2"
		)
		(instances
			(project "gmsl-serializer"
				(path ""
					(reference "C6")
					(unit 1)
				)
			)
		)
	)
	(symbol
		(lib_id "antmicroResistors0603:R_0R_22.4A_0603")
		(at 137.16 204.47 0)
		(unit 1)
		(exclude_from_sim no)
		(in_bom yes)
		(on_board yes)
		(dnp no)
		(property "Reference" "R14"
			(at 139.7 199.39 0)
			(effects
				(font
					(size 1.27 1.27)
					(thickness 0.15)
				)
			)
		)
		(property "Value" "R_0R_22.4A_0603"
			(at 139.7 198.755 0)
			(effects
				(font
					(size 1.27 1.27)
					(thickness 0.15)
				)
				(hide yes)
			)
		)
		(property "Footprint" "antmicro-footprints:R_0603_1608Metric"
			(at 152.4 214.63 0)
			(effects
				(font
					(size 1.27 1.27)
					(thickness 0.15)
				)
				(justify left bottom)
				(hide yes)
			)
		)
		(property "Datasheet" "https://fscdn.rohm.com/en/products/databook/datasheet/passive/resistor/chip_resistor/pmr-jpw-e.pdf"
			(at 152.4 217.17 0)
			(effects
				(font
					(size 1.27 1.27)
					(thickness 0.15)
				)
				(justify left bottom)
				(hide yes)
			)
		)
		(property "Description" ""
			(at 137.16 204.47 0)
			(effects
				(font
					(size 1.27 1.27)
				)
				(hide yes)
			)
		)
		(property "MPN" "PMR03EZPJ000"
			(at 152.4 219.71 0)
			(effects
				(font
					(size 1.27 1.27)
					(thickness 0.15)
				)
				(justify left bottom)
				(hide yes)
			)
		)
		(property "Manufacturer" "ROHM Semiconductor"
			(at 152.4 222.25 0)
			(effects
				(font
					(size 1.27 1.27)
					(thickness 0.15)
				)
				(justify left bottom)
				(hide yes)
			)
		)
		(property "Val" "0R"
			(at 139.7 201.93 0)
			(effects
				(font
					(size 1.27 1.27)
					(thickness 0.15)
				)
			)
		)
		(property "Max. Curr." "22.4A"
			(at 139.7 207.01 0)
			(effects
				(font
					(size 1.27 1.27)
					(thickness 0.15)
				)
			)
		)
		(property "Author" "Antmicro"
			(at 152.4 227.33 0)
			(effects
				(font
					(size 1.27 1.27)
					(thickness 0.15)
				)
				(justify left bottom)
				(hide yes)
			)
		)
		(property "License" "Apache-2.0"
			(at 152.4 229.87 0)
			(effects
				(font
					(size 1.27 1.27)
					(thickness 0.15)
				)
				(justify left bottom)
				(hide yes)
			)
		)
		(property "Tolerance" "template_tolerance"
			(at 157.48 214.63 0)
			(effects
				(font
					(size 1.27 1.27)
				)
				(justify left bottom)
				(hide yes)
			)
		)
		(pin "1"
		)
		(pin "2"
		)
		(instances
			(project "gmsl-serializer"
				(path ""
					(reference "R14")
					(unit 1)
				)
			)
		)
	)
	(symbol
		(lib_id "antmicropower:+12V")
		(at 55.88 203.2 0)
		(unit 1)
		(exclude_from_sim no)
		(in_bom yes)
		(on_board yes)
		(dnp no)
		(fields_autoplaced yes)
		(property "Reference" "#PWR0124"
			(at 55.88 207.01 0)
			(effects
				(font
					(size 1.27 1.27)
				)
				(hide yes)
			)
		)
		(property "Value" "+12V"
			(at 55.88 198.12 0)
			(effects
				(font
					(size 1.27 1.27)
				)
			)
		)
		(property "Footprint" ""
			(at 55.88 203.2 0)
			(effects
				(font
					(size 1.27 1.27)
				)
				(hide yes)
			)
		)
		(property "Datasheet" ""
			(at 55.88 203.2 0)
			(effects
				(font
					(size 1.27 1.27)
				)
				(hide yes)
			)
		)
		(property "Description" ""
			(at 55.88 203.2 0)
			(effects
				(font
					(size 1.27 1.27)
				)
				(hide yes)
			)
		)
		(pin "1"
		)
		(instances
			(project "gmsl-serializer"
				(path ""
					(reference "#PWR0124")
					(unit 1)
				)
			)
		)
	)
	(symbol
		(lib_id "antmicroResistors0402:R_12k4_0402")
		(at 118.11 210.82 90)
		(unit 1)
		(exclude_from_sim no)
		(in_bom yes)
		(on_board yes)
		(dnp no)
		(fields_autoplaced yes)
		(property "Reference" "R11"
			(at 120.015 207.0099 90)
			(effects
				(font
					(size 1.27 1.27)
					(thickness 0.15)
				)
				(justify right)
			)
		)
		(property "Value" "R_12k4_0402"
			(at 130.81 190.5 0)
			(effects
				(font
					(size 1.27 1.27)
					(thickness 0.15)
				)
				(justify left bottom)
				(hide yes)
			)
		)
		(property "Footprint" "antmicro-footprints:R_0402_1005Metric"
			(at 133.35 190.5 0)
			(effects
				(font
					(size 1.27 1.27)
					(thickness 0.15)
				)
				(justify left bottom)
				(hide yes)
			)
		)
		(property "Datasheet" "https://www.bourns.com/docs/product-datasheets/cr.pdf"
			(at 135.89 190.5 0)
			(effects
				(font
					(size 1.27 1.27)
					(thickness 0.15)
				)
				(justify left bottom)
				(hide yes)
			)
		)
		(property "Description" ""
			(at 118.11 210.82 0)
			(effects
				(font
					(size 1.27 1.27)
				)
				(hide yes)
			)
		)
		(property "MPN" "CR0402-FX-1242GLF"
			(at 138.43 190.5 0)
			(effects
				(font
					(size 1.27 1.27)
					(thickness 0.15)
				)
				(justify left bottom)
				(hide yes)
			)
		)
		(property "Manufacturer" "Bourns"
			(at 140.97 190.5 0)
			(effects
				(font
					(size 1.27 1.27)
					(thickness 0.15)
				)
				(justify left bottom)
				(hide yes)
			)
		)
		(property "License" "Apache-2.0"
			(at 143.51 190.5 0)
			(effects
				(font
					(size 1.27 1.27)
					(thickness 0.15)
				)
				(justify left bottom)
				(hide yes)
			)
		)
		(property "Author" "Antmicro"
			(at 146.05 190.5 0)
			(effects
				(font
					(size 1.27 1.27)
					(thickness 0.15)
				)
				(justify left bottom)
				(hide yes)
			)
		)
		(property "Val" "12k4"
			(at 120.015 209.5499 90)
			(effects
				(font
					(size 1.27 1.27)
					(thickness 0.15)
				)
				(justify right)
			)
		)
		(property "Tolerance" "1%"
			(at 128.27 190.5 0)
			(effects
				(font
					(size 1.27 1.27)
				)
				(justify left bottom)
				(hide yes)
			)
		)
		(pin "1"
		)
		(pin "2"
		)
		(instances
			(project "gmsl-serializer"
				(path ""
					(reference "R11")
					(unit 1)
				)
			)
		)
	)
	(symbol
		(lib_id "antmicropower:GND")
		(at 127 223.52 0)
		(unit 1)
		(exclude_from_sim no)
		(in_bom yes)
		(on_board yes)
		(dnp no)
		(property "Reference" "#PWR0112"
			(at 135.89 226.06 0)
			(effects
				(font
					(size 1.27 1.27)
					(thickness 0.15)
				)
				(justify left bottom)
				(hide yes)
			)
		)
		(property "Value" "GND"
			(at 127 227.33 0)
			(effects
				(font
					(size 1.27 1.27)
					(thickness 0.15)
				)
			)
		)
		(property "Footprint" ""
			(at 135.89 231.14 0)
			(effects
				(font
					(size 1.27 1.27)
					(thickness 0.15)
				)
				(justify left bottom)
				(hide yes)
			)
		)
		(property "Datasheet" ""
			(at 135.89 236.22 0)
			(effects
				(font
					(size 1.27 1.27)
					(thickness 0.15)
				)
				(justify left bottom)
				(hide yes)
			)
		)
		(property "Description" ""
			(at 127 223.52 0)
			(effects
				(font
					(size 1.27 1.27)
				)
				(hide yes)
			)
		)
		(property "Author" "Antmicro"
			(at 135.89 231.14 0)
			(effects
				(font
					(size 1.27 1.27)
					(thickness 0.15)
				)
				(justify left bottom)
				(hide yes)
			)
		)
		(property "License" "Apache-2.0"
			(at 135.89 233.68 0)
			(effects
				(font
					(size 1.27 1.27)
					(thickness 0.15)
				)
				(justify left bottom)
				(hide yes)
			)
		)
		(pin "1"
		)
		(instances
			(project "gmsl-serializer"
				(path ""
					(reference "#PWR0112")
					(unit 1)
				)
			)
		)
	)
	(symbol
		(lib_id "antmicroCapacitors0402:C_22u_0402")
		(at 153.67 97.79 90)
		(unit 1)
		(exclude_from_sim no)
		(in_bom yes)
		(on_board yes)
		(dnp no)
		(property "Reference" "C7"
			(at 156.21 93.98 90)
			(effects
				(font
					(size 1.27 1.27)
					(thickness 0.15)
				)
				(justify right)
			)
		)
		(property "Value" "C_22u_0402"
			(at 163.83 77.47 0)
			(effects
				(font
					(size 1.27 1.27)
					(thickness 0.15)
				)
				(justify left bottom)
				(hide yes)
			)
		)
		(property "Footprint" "antmicro-footprints:C_0402_1005Metric"
			(at 166.37 77.47 0)
			(effects
				(font
					(size 1.27 1.27)
					(thickness 0.15)
				)
				(justify left bottom)
				(hide yes)
			)
		)
		(property "Datasheet" "https://www.murata.com/products/productdetail?partno=GRM158R60J226ME01%23"
			(at 168.91 77.47 0)
			(effects
				(font
					(size 1.27 1.27)
					(thickness 0.15)
				)
				(justify left bottom)
				(hide yes)
			)
		)
		(property "Description" ""
			(at 153.67 97.79 0)
			(effects
				(font
					(size 1.27 1.27)
				)
				(hide yes)
			)
		)
		(property "MPN" "GRM158R60J226ME01D"
			(at 171.45 77.47 0)
			(effects
				(font
					(size 1.27 1.27)
					(thickness 0.15)
				)
				(justify left bottom)
				(hide yes)
			)
		)
		(property "Manufacturer" "Murata"
			(at 173.99 77.47 0)
			(effects
				(font
					(size 1.27 1.27)
					(thickness 0.15)
				)
				(justify left bottom)
				(hide yes)
			)
		)
		(property "License" "Apache-2.0"
			(at 176.53 77.47 0)
			(effects
				(font
					(size 1.27 1.27)
					(thickness 0.15)
				)
				(justify left bottom)
				(hide yes)
			)
		)
		(property "Author" "Antmicro"
			(at 179.07 77.47 0)
			(effects
				(font
					(size 1.27 1.27)
					(thickness 0.15)
				)
				(justify left bottom)
				(hide yes)
			)
		)
		(property "Val" "22u"
			(at 156.21 96.52 90)
			(effects
				(font
					(size 1.27 1.27)
					(thickness 0.15)
				)
				(justify right)
			)
		)
		(property "Voltage" ""
			(at 181.61 77.47 0)
			(effects
				(font
					(size 1.27 1.27)
				)
				(justify left bottom)
				(hide yes)
			)
		)
		(property "Dielectric" ""
			(at 184.15 77.47 0)
			(effects
				(font
					(size 1.27 1.27)
				)
				(justify left bottom)
				(hide yes)
			)
		)
		(pin "1"
		)
		(pin "2"
		)
		(instances
			(project "gmsl-serializer"
				(path ""
					(reference "C7")
					(unit 1)
				)
			)
		)
	)
	(symbol
		(lib_id "antmicropower:GND")
		(at 270.51 135.89 0)
		(unit 1)
		(exclude_from_sim no)
		(in_bom yes)
		(on_board yes)
		(dnp no)
		(fields_autoplaced yes)
		(property "Reference" "#PWR0134"
			(at 279.4 138.43 0)
			(effects
				(font
					(size 1.27 1.27)
					(thickness 0.15)
				)
				(justify left bottom)
				(hide yes)
			)
		)
		(property "Value" "GND"
			(at 270.51 140.97 0)
			(effects
				(font
					(size 1.27 1.27)
					(thickness 0.15)
				)
			)
		)
		(property "Footprint" ""
			(at 279.4 143.51 0)
			(effects
				(font
					(size 1.27 1.27)
					(thickness 0.15)
				)
				(justify left bottom)
				(hide yes)
			)
		)
		(property "Datasheet" ""
			(at 279.4 148.59 0)
			(effects
				(font
					(size 1.27 1.27)
					(thickness 0.15)
				)
				(justify left bottom)
				(hide yes)
			)
		)
		(property "Description" ""
			(at 270.51 135.89 0)
			(effects
				(font
					(size 1.27 1.27)
				)
				(hide yes)
			)
		)
		(property "Author" "Antmicro"
			(at 279.4 143.51 0)
			(effects
				(font
					(size 1.27 1.27)
					(thickness 0.15)
				)
				(justify left bottom)
				(hide yes)
			)
		)
		(property "License" "Apache-2.0"
			(at 279.4 146.05 0)
			(effects
				(font
					(size 1.27 1.27)
					(thickness 0.15)
				)
				(justify left bottom)
				(hide yes)
			)
		)
		(pin "1"
		)
		(instances
			(project "gmsl-serializer"
				(path ""
					(reference "#PWR0134")
					(unit 1)
				)
			)
		)
	)
	(symbol
		(lib_id "antmicroTestPoints:TP_1.5mm_SMD")
		(at 353.06 201.93 0)
		(unit 1)
		(exclude_from_sim no)
		(in_bom no)
		(on_board yes)
		(dnp no)
		(property "Reference" "TP4"
			(at 358.14 200.66 0)
			(effects
				(font
					(size 1.27 1.27)
					(thickness 0.15)
				)
				(justify right)
			)
		)
		(property "Value" "TP_1.5mm_SMD"
			(at 368.3 209.55 0)
			(effects
				(font
					(size 1.27 1.27)
					(thickness 0.15)
				)
				(justify left bottom)
				(hide yes)
			)
		)
		(property "Footprint" "antmicro-footprints:TP_SMD_1.5mm"
			(at 368.3 212.09 0)
			(effects
				(font
					(size 1.27 1.27)
					(thickness 0.15)
				)
				(justify left bottom)
				(hide yes)
			)
		)
		(property "Datasheet" ""
			(at 370.84 214.63 0)
			(effects
				(font
					(size 1.27 1.27)
					(thickness 0.15)
				)
				(justify left bottom)
				(hide yes)
			)
		)
		(property "Description" ""
			(at 353.06 201.93 0)
			(effects
				(font
					(size 1.27 1.27)
				)
				(hide yes)
			)
		)
		(property "MPN" ""
			(at 353.06 201.93 0)
			(effects
				(font
					(size 1.27 1.27)
				)
				(hide yes)
			)
		)
		(property "Manufacturer" ""
			(at 353.06 201.93 0)
			(effects
				(font
					(size 1.27 1.27)
				)
				(hide yes)
			)
		)
		(property "Author" "Antmicro"
			(at 368.3 217.17 0)
			(effects
				(font
					(size 1.27 1.27)
					(thickness 0.15)
				)
				(justify left bottom)
				(hide yes)
			)
		)
		(property "License" "Apache-2.0"
			(at 368.3 219.71 0)
			(effects
				(font
					(size 1.27 1.27)
					(thickness 0.15)
				)
				(justify left bottom)
				(hide yes)
			)
		)
		(pin "1"
		)
		(instances
			(project "gmsl-serializer"
				(path ""
					(reference "TP4")
					(unit 1)
				)
			)
		)
	)
	(symbol
		(lib_id "antmicroCapacitors0402:C_220n_0402")
		(at 118.11 86.36 0)
		(unit 1)
		(exclude_from_sim no)
		(in_bom yes)
		(on_board yes)
		(dnp no)
		(property "Reference" "C3"
			(at 124.46 85.09 0)
			(effects
				(font
					(size 1.27 1.27)
					(thickness 0.15)
				)
			)
		)
		(property "Value" "C_220n_0402"
			(at 138.43 96.52 0)
			(effects
				(font
					(size 1.27 1.27)
					(thickness 0.15)
				)
				(justify left bottom)
				(hide yes)
			)
		)
		(property "Footprint" "antmicro-footprints:C_0402_1005Metric"
			(at 138.43 99.06 0)
			(effects
				(font
					(size 1.27 1.27)
					(thickness 0.15)
				)
				(justify left bottom)
				(hide yes)
			)
		)
		(property "Datasheet" "https://www.yageo.com/en/Chart/Download/pdf/CC0402KRX5R6BB224"
			(at 138.43 101.6 0)
			(effects
				(font
					(size 1.27 1.27)
					(thickness 0.15)
				)
				(justify left bottom)
				(hide yes)
			)
		)
		(property "Description" ""
			(at 118.11 86.36 0)
			(effects
				(font
					(size 1.27 1.27)
				)
				(hide yes)
			)
		)
		(property "MPN" "CC0402KRX5R6BB224"
			(at 138.43 104.14 0)
			(effects
				(font
					(size 1.27 1.27)
					(thickness 0.15)
				)
				(justify left bottom)
				(hide yes)
			)
		)
		(property "Manufacturer" "YAGEO"
			(at 138.43 106.68 0)
			(effects
				(font
					(size 1.27 1.27)
					(thickness 0.15)
				)
				(justify left bottom)
				(hide yes)
			)
		)
		(property "License" "Apache-2.0"
			(at 138.43 109.22 0)
			(effects
				(font
					(size 1.27 1.27)
					(thickness 0.15)
				)
				(justify left bottom)
				(hide yes)
			)
		)
		(property "Author" "Antmicro"
			(at 138.43 111.76 0)
			(effects
				(font
					(size 1.27 1.27)
					(thickness 0.15)
				)
				(justify left bottom)
				(hide yes)
			)
		)
		(property "Val" "220n"
			(at 125.73 87.63 0)
			(effects
				(font
					(size 1.27 1.27)
					(thickness 0.15)
				)
			)
		)
		(property "Voltage" ""
			(at 138.43 114.3 0)
			(effects
				(font
					(size 1.27 1.27)
				)
				(justify left bottom)
				(hide yes)
			)
		)
		(property "Dielectric" ""
			(at 138.43 116.84 0)
			(effects
				(font
					(size 1.27 1.27)
				)
				(justify left bottom)
				(hide yes)
			)
		)
		(pin "1"
		)
		(pin "2"
		)
		(instances
			(project "gmsl-serializer"
				(path ""
					(reference "C3")
					(unit 1)
				)
			)
		)
	)
	(symbol
		(lib_id "antmicropower:GND")
		(at 95.25 92.71 0)
		(unit 1)
		(exclude_from_sim no)
		(in_bom yes)
		(on_board yes)
		(dnp no)
		(property "Reference" "#PWR0122"
			(at 104.14 95.25 0)
			(effects
				(font
					(size 1.27 1.27)
					(thickness 0.15)
				)
				(justify left bottom)
				(hide yes)
			)
		)
		(property "Value" "GND"
			(at 95.25 96.52 0)
			(effects
				(font
					(size 1.27 1.27)
					(thickness 0.15)
				)
			)
		)
		(property "Footprint" ""
			(at 104.14 100.33 0)
			(effects
				(font
					(size 1.27 1.27)
					(thickness 0.15)
				)
				(justify left bottom)
				(hide yes)
			)
		)
		(property "Datasheet" ""
			(at 104.14 105.41 0)
			(effects
				(font
					(size 1.27 1.27)
					(thickness 0.15)
				)
				(justify left bottom)
				(hide yes)
			)
		)
		(property "Description" ""
			(at 95.25 92.71 0)
			(effects
				(font
					(size 1.27 1.27)
				)
				(hide yes)
			)
		)
		(property "Author" "Antmicro"
			(at 104.14 100.33 0)
			(effects
				(font
					(size 1.27 1.27)
					(thickness 0.15)
				)
				(justify left bottom)
				(hide yes)
			)
		)
		(property "License" "Apache-2.0"
			(at 104.14 102.87 0)
			(effects
				(font
					(size 1.27 1.27)
					(thickness 0.15)
				)
				(justify left bottom)
				(hide yes)
			)
		)
		(pin "1"
		)
		(instances
			(project "gmsl-serializer"
				(path ""
					(reference "#PWR0122")
					(unit 1)
				)
			)
		)
	)
	(symbol
		(lib_id "antmicropower:GND")
		(at 165.1 99.06 0)
		(unit 1)
		(exclude_from_sim no)
		(in_bom yes)
		(on_board yes)
		(dnp no)
		(property "Reference" "#PWR03"
			(at 173.99 101.6 0)
			(effects
				(font
					(size 1.27 1.27)
					(thickness 0.15)
				)
				(justify left bottom)
				(hide yes)
			)
		)
		(property "Value" "GND"
			(at 165.1 102.87 0)
			(effects
				(font
					(size 1.27 1.27)
					(thickness 0.15)
				)
			)
		)
		(property "Footprint" ""
			(at 173.99 106.68 0)
			(effects
				(font
					(size 1.27 1.27)
					(thickness 0.15)
				)
				(justify left bottom)
				(hide yes)
			)
		)
		(property "Datasheet" ""
			(at 173.99 111.76 0)
			(effects
				(font
					(size 1.27 1.27)
					(thickness 0.15)
				)
				(justify left bottom)
				(hide yes)
			)
		)
		(property "Description" ""
			(at 165.1 99.06 0)
			(effects
				(font
					(size 1.27 1.27)
				)
				(hide yes)
			)
		)
		(property "Author" "Antmicro"
			(at 173.99 106.68 0)
			(effects
				(font
					(size 1.27 1.27)
					(thickness 0.15)
				)
				(justify left bottom)
				(hide yes)
			)
		)
		(property "License" "Apache-2.0"
			(at 173.99 109.22 0)
			(effects
				(font
					(size 1.27 1.27)
					(thickness 0.15)
				)
				(justify left bottom)
				(hide yes)
			)
		)
		(pin "1"
		)
		(instances
			(project "gmsl-serializer"
				(path ""
					(reference "#PWR03")
					(unit 1)
				)
			)
		)
	)
	(symbol
		(lib_id "antmicroResistors0402:R_10k_0402")
		(at 118.11 222.25 90)
		(unit 1)
		(exclude_from_sim no)
		(in_bom yes)
		(on_board yes)
		(dnp no)
		(fields_autoplaced yes)
		(property "Reference" "R12"
			(at 120.015 218.4399 90)
			(effects
				(font
					(size 1.27 1.27)
					(thickness 0.15)
				)
				(justify right)
			)
		)
		(property "Value" "R_10k_0402"
			(at 130.81 201.93 0)
			(effects
				(font
					(size 1.27 1.27)
					(thickness 0.15)
				)
				(justify left bottom)
				(hide yes)
			)
		)
		(property "Footprint" "antmicro-footprints:R_0402_1005Metric"
			(at 133.35 201.93 0)
			(effects
				(font
					(size 1.27 1.27)
					(thickness 0.15)
				)
				(justify left bottom)
				(hide yes)
			)
		)
		(property "Datasheet" "https://www.bourns.com/docs/product-datasheets/cr.pdf"
			(at 135.89 201.93 0)
			(effects
				(font
					(size 1.27 1.27)
					(thickness 0.15)
				)
				(justify left bottom)
				(hide yes)
			)
		)
		(property "Description" ""
			(at 118.11 222.25 0)
			(effects
				(font
					(size 1.27 1.27)
				)
				(hide yes)
			)
		)
		(property "MPN" "CR0402-FX-1002GLF"
			(at 138.43 201.93 0)
			(effects
				(font
					(size 1.27 1.27)
					(thickness 0.15)
				)
				(justify left bottom)
				(hide yes)
			)
		)
		(property "Manufacturer" "Bourns"
			(at 140.97 201.93 0)
			(effects
				(font
					(size 1.27 1.27)
					(thickness 0.15)
				)
				(justify left bottom)
				(hide yes)
			)
		)
		(property "License" "Apache-2.0"
			(at 143.51 201.93 0)
			(effects
				(font
					(size 1.27 1.27)
					(thickness 0.15)
				)
				(justify left bottom)
				(hide yes)
			)
		)
		(property "Author" "Antmicro"
			(at 146.05 201.93 0)
			(effects
				(font
					(size 1.27 1.27)
					(thickness 0.15)
				)
				(justify left bottom)
				(hide yes)
			)
		)
		(property "Val" "10k"
			(at 120.015 220.9799 90)
			(effects
				(font
					(size 1.27 1.27)
					(thickness 0.15)
				)
				(justify right)
			)
		)
		(property "Tolerance" "1%"
			(at 128.27 201.93 0)
			(effects
				(font
					(size 1.27 1.27)
				)
				(justify left bottom)
				(hide yes)
			)
		)
		(pin "1"
		)
		(pin "2"
		)
		(instances
			(project "gmsl-serializer"
				(path ""
					(reference "R12")
					(unit 1)
				)
			)
		)
	)
	(symbol
		(lib_id "antmicroResistors0402:R_10k_0402")
		(at 321.31 218.44 90)
		(unit 1)
		(exclude_from_sim no)
		(in_bom yes)
		(on_board yes)
		(dnp no)
		(fields_autoplaced yes)
		(property "Reference" "R44"
			(at 323.215 214.6299 90)
			(effects
				(font
					(size 1.27 1.27)
					(thickness 0.15)
				)
				(justify right)
			)
		)
		(property "Value" "R_10k_0402"
			(at 334.01 198.12 0)
			(effects
				(font
					(size 1.27 1.27)
					(thickness 0.15)
				)
				(justify left bottom)
				(hide yes)
			)
		)
		(property "Footprint" "antmicro-footprints:R_0402_1005Metric"
			(at 336.55 198.12 0)
			(effects
				(font
					(size 1.27 1.27)
					(thickness 0.15)
				)
				(justify left bottom)
				(hide yes)
			)
		)
		(property "Datasheet" "https://www.bourns.com/docs/product-datasheets/cr.pdf"
			(at 339.09 198.12 0)
			(effects
				(font
					(size 1.27 1.27)
					(thickness 0.15)
				)
				(justify left bottom)
				(hide yes)
			)
		)
		(property "Description" ""
			(at 321.31 218.44 0)
			(effects
				(font
					(size 1.27 1.27)
				)
				(hide yes)
			)
		)
		(property "MPN" "CR0402-FX-1002GLF"
			(at 341.63 198.12 0)
			(effects
				(font
					(size 1.27 1.27)
					(thickness 0.15)
				)
				(justify left bottom)
				(hide yes)
			)
		)
		(property "Manufacturer" "Bourns"
			(at 344.17 198.12 0)
			(effects
				(font
					(size 1.27 1.27)
					(thickness 0.15)
				)
				(justify left bottom)
				(hide yes)
			)
		)
		(property "License" "Apache-2.0"
			(at 346.71 198.12 0)
			(effects
				(font
					(size 1.27 1.27)
					(thickness 0.15)
				)
				(justify left bottom)
				(hide yes)
			)
		)
		(property "Author" "Antmicro"
			(at 349.25 198.12 0)
			(effects
				(font
					(size 1.27 1.27)
					(thickness 0.15)
				)
				(justify left bottom)
				(hide yes)
			)
		)
		(property "Val" "10k"
			(at 323.215 217.1699 90)
			(effects
				(font
					(size 1.27 1.27)
					(thickness 0.15)
				)
				(justify right)
			)
		)
		(property "Tolerance" "1%"
			(at 331.47 198.12 0)
			(effects
				(font
					(size 1.27 1.27)
				)
				(justify left bottom)
				(hide yes)
			)
		)
		(pin "1"
		)
		(pin "2"
		)
		(instances
			(project "gmsl-serializer"
				(path ""
					(reference "R44")
					(unit 1)
				)
			)
		)
	)
	(symbol
		(lib_id "antmicropower:PWR_FLAG")
		(at 346.71 193.04 0)
		(unit 1)
		(exclude_from_sim no)
		(in_bom yes)
		(on_board yes)
		(dnp no)
		(property "Reference" "#FLG05"
			(at 346.71 191.135 0)
			(effects
				(font
					(size 1.27 1.27)
				)
				(hide yes)
			)
		)
		(property "Value" "PWR_FLAG"
			(at 339.09 190.5 0)
			(effects
				(font
					(size 1.27 1.27)
				)
			)
		)
		(property "Footprint" ""
			(at 346.71 193.04 0)
			(effects
				(font
					(size 1.27 1.27)
				)
				(hide yes)
			)
		)
		(property "Datasheet" ""
			(at 346.71 193.04 0)
			(effects
				(font
					(size 1.27 1.27)
				)
				(hide yes)
			)
		)
		(property "Description" ""
			(at 346.71 193.04 0)
			(effects
				(font
					(size 1.27 1.27)
				)
				(hide yes)
			)
		)
		(pin "1"
		)
		(instances
			(project "gmsl-serializer"
				(path ""
					(reference "#FLG05")
					(unit 1)
				)
			)
		)
	)
	(symbol
		(lib_id "antmicropower:GND")
		(at 339.09 219.71 0)
		(unit 1)
		(exclude_from_sim no)
		(in_bom yes)
		(on_board yes)
		(dnp no)
		(property "Reference" "#PWR028"
			(at 347.98 222.25 0)
			(effects
				(font
					(size 1.27 1.27)
					(thickness 0.15)
				)
				(justify left bottom)
				(hide yes)
			)
		)
		(property "Value" "GND"
			(at 339.09 223.52 0)
			(effects
				(font
					(size 1.27 1.27)
					(thickness 0.15)
				)
			)
		)
		(property "Footprint" ""
			(at 347.98 227.33 0)
			(effects
				(font
					(size 1.27 1.27)
					(thickness 0.15)
				)
				(justify left bottom)
				(hide yes)
			)
		)
		(property "Datasheet" ""
			(at 347.98 232.41 0)
			(effects
				(font
					(size 1.27 1.27)
					(thickness 0.15)
				)
				(justify left bottom)
				(hide yes)
			)
		)
		(property "Description" ""
			(at 339.09 219.71 0)
			(effects
				(font
					(size 1.27 1.27)
				)
				(hide yes)
			)
		)
		(property "Author" "Antmicro"
			(at 347.98 227.33 0)
			(effects
				(font
					(size 1.27 1.27)
					(thickness 0.15)
				)
				(justify left bottom)
				(hide yes)
			)
		)
		(property "License" "Apache-2.0"
			(at 347.98 229.87 0)
			(effects
				(font
					(size 1.27 1.27)
					(thickness 0.15)
				)
				(justify left bottom)
				(hide yes)
			)
		)
		(pin "1"
		)
		(instances
			(project "gmsl-serializer"
				(path ""
					(reference "#PWR028")
					(unit 1)
				)
			)
		)
	)
	(symbol
		(lib_id "antmicroCapacitors0402:C_1u_16V_0402")
		(at 311.15 134.62 90)
		(unit 1)
		(exclude_from_sim no)
		(in_bom yes)
		(on_board yes)
		(dnp no)
		(property "Reference" "C15"
			(at 313.69 130.81 90)
			(effects
				(font
					(size 1.27 1.27)
					(thickness 0.15)
				)
				(justify right)
			)
		)
		(property "Value" "C_1u_16V_0402"
			(at 321.31 114.3 0)
			(effects
				(font
					(size 1.27 1.27)
					(thickness 0.15)
				)
				(justify left bottom)
				(hide yes)
			)
		)
		(property "Footprint" "antmicro-footprints:C_0402_1005Metric"
			(at 323.85 114.3 0)
			(effects
				(font
					(size 1.27 1.27)
					(thickness 0.15)
				)
				(justify left bottom)
				(hide yes)
			)
		)
		(property "Datasheet" "https://www.kemet.com/en/us/capacitors/product/C0402C105M4PACTU.html"
			(at 326.39 114.3 0)
			(effects
				(font
					(size 1.27 1.27)
					(thickness 0.15)
				)
				(justify left bottom)
				(hide yes)
			)
		)
		(property "Description" ""
			(at 311.15 134.62 0)
			(effects
				(font
					(size 1.27 1.27)
				)
				(hide yes)
			)
		)
		(property "MPN" "C0402C105M4PACTU"
			(at 328.93 114.3 0)
			(effects
				(font
					(size 1.27 1.27)
					(thickness 0.15)
				)
				(justify left bottom)
				(hide yes)
			)
		)
		(property "Manufacturer" "KEMET"
			(at 331.47 114.3 0)
			(effects
				(font
					(size 1.27 1.27)
					(thickness 0.15)
				)
				(justify left bottom)
				(hide yes)
			)
		)
		(property "License" "Apache-2.0"
			(at 334.01 114.3 0)
			(effects
				(font
					(size 1.27 1.27)
					(thickness 0.15)
				)
				(justify left bottom)
				(hide yes)
			)
		)
		(property "Author" "Antmicro"
			(at 336.55 114.3 0)
			(effects
				(font
					(size 1.27 1.27)
					(thickness 0.15)
				)
				(justify left bottom)
				(hide yes)
			)
		)
		(property "Val" "1u"
			(at 313.69 133.35 90)
			(effects
				(font
					(size 1.27 1.27)
					(thickness 0.15)
				)
				(justify right)
			)
		)
		(property "Voltage" "16V"
			(at 339.09 114.3 0)
			(effects
				(font
					(size 1.27 1.27)
				)
				(justify left bottom)
				(hide yes)
			)
		)
		(property "Dielectric" ""
			(at 341.63 114.3 0)
			(effects
				(font
					(size 1.27 1.27)
				)
				(justify left bottom)
				(hide yes)
			)
		)
		(pin "1"
		)
		(pin "2"
		)
		(instances
			(project "gmsl-serializer"
				(path ""
					(reference "C15")
					(unit 1)
				)
			)
		)
	)
	(symbol
		(lib_id "antmicropower:GND")
		(at 280.67 213.36 0)
		(unit 1)
		(exclude_from_sim no)
		(in_bom yes)
		(on_board yes)
		(dnp no)
		(property "Reference" "#PWR025"
			(at 289.56 215.9 0)
			(effects
				(font
					(size 1.27 1.27)
					(thickness 0.15)
				)
				(justify left bottom)
				(hide yes)
			)
		)
		(property "Value" "GND"
			(at 280.67 217.17 0)
			(effects
				(font
					(size 1.27 1.27)
					(thickness 0.15)
				)
			)
		)
		(property "Footprint" ""
			(at 289.56 220.98 0)
			(effects
				(font
					(size 1.27 1.27)
					(thickness 0.15)
				)
				(justify left bottom)
				(hide yes)
			)
		)
		(property "Datasheet" ""
			(at 289.56 226.06 0)
			(effects
				(font
					(size 1.27 1.27)
					(thickness 0.15)
				)
				(justify left bottom)
				(hide yes)
			)
		)
		(property "Description" ""
			(at 280.67 213.36 0)
			(effects
				(font
					(size 1.27 1.27)
				)
				(hide yes)
			)
		)
		(property "Author" "Antmicro"
			(at 289.56 220.98 0)
			(effects
				(font
					(size 1.27 1.27)
					(thickness 0.15)
				)
				(justify left bottom)
				(hide yes)
			)
		)
		(property "License" "Apache-2.0"
			(at 289.56 223.52 0)
			(effects
				(font
					(size 1.27 1.27)
					(thickness 0.15)
				)
				(justify left bottom)
				(hide yes)
			)
		)
		(pin "1"
		)
		(instances
			(project "gmsl-serializer"
				(path ""
					(reference "#PWR025")
					(unit 1)
				)
			)
		)
	)
	(symbol
		(lib_id "antmicroCapacitors0402:C_22u_0402")
		(at 144.78 97.79 90)
		(unit 1)
		(exclude_from_sim no)
		(in_bom yes)
		(on_board yes)
		(dnp no)
		(property "Reference" "C5"
			(at 147.32 93.98 90)
			(effects
				(font
					(size 1.27 1.27)
					(thickness 0.15)
				)
				(justify right)
			)
		)
		(property "Value" "C_22u_0402"
			(at 154.94 77.47 0)
			(effects
				(font
					(size 1.27 1.27)
					(thickness 0.15)
				)
				(justify left bottom)
				(hide yes)
			)
		)
		(property "Footprint" "antmicro-footprints:C_0402_1005Metric"
			(at 157.48 77.47 0)
			(effects
				(font
					(size 1.27 1.27)
					(thickness 0.15)
				)
				(justify left bottom)
				(hide yes)
			)
		)
		(property "Datasheet" "https://www.murata.com/products/productdetail?partno=GRM158R60J226ME01%23"
			(at 160.02 77.47 0)
			(effects
				(font
					(size 1.27 1.27)
					(thickness 0.15)
				)
				(justify left bottom)
				(hide yes)
			)
		)
		(property "Description" ""
			(at 144.78 97.79 0)
			(effects
				(font
					(size 1.27 1.27)
				)
				(hide yes)
			)
		)
		(property "MPN" "GRM158R60J226ME01D"
			(at 162.56 77.47 0)
			(effects
				(font
					(size 1.27 1.27)
					(thickness 0.15)
				)
				(justify left bottom)
				(hide yes)
			)
		)
		(property "Manufacturer" "Murata"
			(at 165.1 77.47 0)
			(effects
				(font
					(size 1.27 1.27)
					(thickness 0.15)
				)
				(justify left bottom)
				(hide yes)
			)
		)
		(property "License" "Apache-2.0"
			(at 167.64 77.47 0)
			(effects
				(font
					(size 1.27 1.27)
					(thickness 0.15)
				)
				(justify left bottom)
				(hide yes)
			)
		)
		(property "Author" "Antmicro"
			(at 170.18 77.47 0)
			(effects
				(font
					(size 1.27 1.27)
					(thickness 0.15)
				)
				(justify left bottom)
				(hide yes)
			)
		)
		(property "Val" "22u"
			(at 147.32 96.52 90)
			(effects
				(font
					(size 1.27 1.27)
					(thickness 0.15)
				)
				(justify right)
			)
		)
		(property "Voltage" ""
			(at 172.72 77.47 0)
			(effects
				(font
					(size 1.27 1.27)
				)
				(justify left bottom)
				(hide yes)
			)
		)
		(property "Dielectric" ""
			(at 175.26 77.47 0)
			(effects
				(font
					(size 1.27 1.27)
				)
				(justify left bottom)
				(hide yes)
			)
		)
		(pin "1"
		)
		(pin "2"
		)
		(instances
			(project "gmsl-serializer"
				(path ""
					(reference "C5")
					(unit 1)
				)
			)
		)
	)
	(symbol
		(lib_id "antmicropower:PWR_FLAG")
		(at 161.29 72.39 0)
		(unit 1)
		(exclude_from_sim no)
		(in_bom yes)
		(on_board yes)
		(dnp no)
		(property "Reference" "#FLG0101"
			(at 161.29 70.485 0)
			(effects
				(font
					(size 1.27 1.27)
				)
				(hide yes)
			)
		)
		(property "Value" "PWR_FLAG"
			(at 153.67 69.85 0)
			(effects
				(font
					(size 1.27 1.27)
				)
			)
		)
		(property "Footprint" ""
			(at 161.29 72.39 0)
			(effects
				(font
					(size 1.27 1.27)
				)
				(hide yes)
			)
		)
		(property "Datasheet" ""
			(at 161.29 72.39 0)
			(effects
				(font
					(size 1.27 1.27)
				)
				(hide yes)
			)
		)
		(property "Description" ""
			(at 161.29 72.39 0)
			(effects
				(font
					(size 1.27 1.27)
				)
				(hide yes)
			)
		)
		(pin "1"
		)
		(instances
			(project "gmsl-serializer"
				(path ""
					(reference "#FLG0101")
					(unit 1)
				)
			)
		)
	)
	(symbol
		(lib_id "antmicroResistors0603:R_0R_22.4A_0603")
		(at 340.36 201.93 0)
		(unit 1)
		(exclude_from_sim no)
		(in_bom yes)
		(on_board yes)
		(dnp no)
		(property "Reference" "R45"
			(at 342.9 196.85 0)
			(effects
				(font
					(size 1.27 1.27)
					(thickness 0.15)
				)
			)
		)
		(property "Value" "R_0R_22.4A_0603"
			(at 342.9 196.215 0)
			(effects
				(font
					(size 1.27 1.27)
					(thickness 0.15)
				)
				(hide yes)
			)
		)
		(property "Footprint" "antmicro-footprints:R_0603_1608Metric"
			(at 355.6 212.09 0)
			(effects
				(font
					(size 1.27 1.27)
					(thickness 0.15)
				)
				(justify left bottom)
				(hide yes)
			)
		)
		(property "Datasheet" "https://fscdn.rohm.com/en/products/databook/datasheet/passive/resistor/chip_resistor/pmr-jpw-e.pdf"
			(at 355.6 214.63 0)
			(effects
				(font
					(size 1.27 1.27)
					(thickness 0.15)
				)
				(justify left bottom)
				(hide yes)
			)
		)
		(property "Description" ""
			(at 340.36 201.93 0)
			(effects
				(font
					(size 1.27 1.27)
				)
				(hide yes)
			)
		)
		(property "MPN" "PMR03EZPJ000"
			(at 355.6 217.17 0)
			(effects
				(font
					(size 1.27 1.27)
					(thickness 0.15)
				)
				(justify left bottom)
				(hide yes)
			)
		)
		(property "Manufacturer" "ROHM Semiconductor"
			(at 355.6 219.71 0)
			(effects
				(font
					(size 1.27 1.27)
					(thickness 0.15)
				)
				(justify left bottom)
				(hide yes)
			)
		)
		(property "Val" "0R"
			(at 342.9 199.39 0)
			(effects
				(font
					(size 1.27 1.27)
					(thickness 0.15)
				)
			)
		)
		(property "Max. Curr." "22.4A"
			(at 342.9 204.47 0)
			(effects
				(font
					(size 1.27 1.27)
					(thickness 0.15)
				)
			)
		)
		(property "Author" "Antmicro"
			(at 355.6 224.79 0)
			(effects
				(font
					(size 1.27 1.27)
					(thickness 0.15)
				)
				(justify left bottom)
				(hide yes)
			)
		)
		(property "License" "Apache-2.0"
			(at 355.6 227.33 0)
			(effects
				(font
					(size 1.27 1.27)
					(thickness 0.15)
				)
				(justify left bottom)
				(hide yes)
			)
		)
		(property "Tolerance" "template_tolerance"
			(at 360.68 212.09 0)
			(effects
				(font
					(size 1.27 1.27)
				)
				(justify left bottom)
				(hide yes)
			)
		)
		(pin "1"
		)
		(pin "2"
		)
		(instances
			(project "gmsl-serializer"
				(path ""
					(reference "R45")
					(unit 1)
				)
			)
		)
	)
	(symbol
		(lib_id "antmicropower:GND")
		(at 350.52 219.71 0)
		(unit 1)
		(exclude_from_sim no)
		(in_bom yes)
		(on_board yes)
		(dnp no)
		(property "Reference" "#PWR030"
			(at 359.41 222.25 0)
			(effects
				(font
					(size 1.27 1.27)
					(thickness 0.15)
				)
				(justify left bottom)
				(hide yes)
			)
		)
		(property "Value" "GND"
			(at 350.52 223.52 0)
			(effects
				(font
					(size 1.27 1.27)
					(thickness 0.15)
				)
			)
		)
		(property "Footprint" ""
			(at 359.41 227.33 0)
			(effects
				(font
					(size 1.27 1.27)
					(thickness 0.15)
				)
				(justify left bottom)
				(hide yes)
			)
		)
		(property "Datasheet" ""
			(at 359.41 232.41 0)
			(effects
				(font
					(size 1.27 1.27)
					(thickness 0.15)
				)
				(justify left bottom)
				(hide yes)
			)
		)
		(property "Description" ""
			(at 350.52 219.71 0)
			(effects
				(font
					(size 1.27 1.27)
				)
				(hide yes)
			)
		)
		(property "Author" "Antmicro"
			(at 359.41 227.33 0)
			(effects
				(font
					(size 1.27 1.27)
					(thickness 0.15)
				)
				(justify left bottom)
				(hide yes)
			)
		)
		(property "License" "Apache-2.0"
			(at 359.41 229.87 0)
			(effects
				(font
					(size 1.27 1.27)
					(thickness 0.15)
				)
				(justify left bottom)
				(hide yes)
			)
		)
		(pin "1"
		)
		(instances
			(project "gmsl-serializer"
				(path ""
					(reference "#PWR030")
					(unit 1)
				)
			)
		)
	)
	(symbol
		(lib_id "antmicroLEDIndicationDiscrete:LED_G_0603_LTST-C190GKT")
		(at 171.45 217.17 270)
		(mirror x)
		(unit 1)
		(exclude_from_sim no)
		(in_bom yes)
		(on_board yes)
		(dnp no)
		(property "Reference" "D8"
			(at 175.26 213.36 90)
			(effects
				(font
					(size 1.27 1.27)
					(thickness 0.15)
				)
				(justify left)
			)
		)
		(property "Value" "LED_G_0603_LTST-C190GKT"
			(at 142.875 212.09 90)
			(effects
				(font
					(size 1.27 1.27)
					(thickness 0.15)
				)
				(justify left)
				(hide yes)
			)
		)
		(property "Footprint" "antmicro-footprints:LED_0603_1608Metric_G"
			(at 161.29 194.31 0)
			(effects
				(font
					(size 1.27 1.27)
					(thickness 0.15)
				)
				(justify left bottom)
				(hide yes)
			)
		)
		(property "Datasheet" "https://media.digikey.com/pdf/Data%20Sheets/Lite-On%20PDFs/LTST-C190GKT.pdf"
			(at 158.75 194.31 0)
			(effects
				(font
					(size 1.27 1.27)
					(thickness 0.15)
				)
				(justify left bottom)
				(hide yes)
			)
		)
		(property "Description" ""
			(at 171.45 217.17 0)
			(effects
				(font
					(size 1.27 1.27)
				)
				(hide yes)
			)
		)
		(property "MPN" "LTST-C190GKT"
			(at 175.26 214.63 90)
			(effects
				(font
					(size 1.27 1.27)
					(thickness 0.15)
				)
				(justify left bottom)
			)
		)
		(property "Manufacturer" "Lite-On"
			(at 153.67 194.31 0)
			(effects
				(font
					(size 1.27 1.27)
					(thickness 0.15)
				)
				(justify left bottom)
				(hide yes)
			)
		)
		(property "Author" "Antmicro"
			(at 151.13 194.31 0)
			(effects
				(font
					(size 1.27 1.27)
					(thickness 0.15)
				)
				(justify left bottom)
				(hide yes)
			)
		)
		(property "License" "Apache-2.0"
			(at 148.59 194.31 0)
			(effects
				(font
					(size 1.27 1.27)
					(thickness 0.15)
				)
				(justify left bottom)
				(hide yes)
			)
		)
		(property "VSD_class" "LED"
			(at 146.05 194.31 0)
			(effects
				(font
					(size 1.27 1.27)
				)
				(justify left bottom)
				(hide yes)
			)
		)
		(property "Color" "Green"
			(at 166.37 194.31 0)
			(effects
				(font
					(size 1.27 1.27)
				)
				(justify left bottom)
				(hide yes)
			)
		)
		(pin "1"
		)
		(pin "2"
		)
		(instances
			(project "gmsl-serializer"
				(path ""
					(reference "D8")
					(unit 1)
				)
			)
		)
	)
	(symbol
		(lib_id "antmicropower:GND")
		(at 330.2 219.71 0)
		(unit 1)
		(exclude_from_sim no)
		(in_bom yes)
		(on_board yes)
		(dnp no)
		(property "Reference" "#PWR027"
			(at 339.09 222.25 0)
			(effects
				(font
					(size 1.27 1.27)
					(thickness 0.15)
				)
				(justify left bottom)
				(hide yes)
			)
		)
		(property "Value" "GND"
			(at 330.2 223.52 0)
			(effects
				(font
					(size 1.27 1.27)
					(thickness 0.15)
				)
			)
		)
		(property "Footprint" ""
			(at 339.09 227.33 0)
			(effects
				(font
					(size 1.27 1.27)
					(thickness 0.15)
				)
				(justify left bottom)
				(hide yes)
			)
		)
		(property "Datasheet" ""
			(at 339.09 232.41 0)
			(effects
				(font
					(size 1.27 1.27)
					(thickness 0.15)
				)
				(justify left bottom)
				(hide yes)
			)
		)
		(property "Description" ""
			(at 330.2 219.71 0)
			(effects
				(font
					(size 1.27 1.27)
				)
				(hide yes)
			)
		)
		(property "Author" "Antmicro"
			(at 339.09 227.33 0)
			(effects
				(font
					(size 1.27 1.27)
					(thickness 0.15)
				)
				(justify left bottom)
				(hide yes)
			)
		)
		(property "License" "Apache-2.0"
			(at 339.09 229.87 0)
			(effects
				(font
					(size 1.27 1.27)
					(thickness 0.15)
				)
				(justify left bottom)
				(hide yes)
			)
		)
		(pin "1"
		)
		(instances
			(project "gmsl-serializer"
				(path ""
					(reference "#PWR027")
					(unit 1)
				)
			)
		)
	)
	(symbol
		(lib_id "antmicropower:+12V")
		(at 254 199.39 0)
		(unit 1)
		(exclude_from_sim no)
		(in_bom yes)
		(on_board yes)
		(dnp no)
		(fields_autoplaced yes)
		(property "Reference" "#PWR020"
			(at 254 203.2 0)
			(effects
				(font
					(size 1.27 1.27)
				)
				(hide yes)
			)
		)
		(property "Value" "+12V"
			(at 254 194.31 0)
			(effects
				(font
					(size 1.27 1.27)
				)
			)
		)
		(property "Footprint" ""
			(at 254 199.39 0)
			(effects
				(font
					(size 1.27 1.27)
				)
				(hide yes)
			)
		)
		(property "Datasheet" ""
			(at 254 199.39 0)
			(effects
				(font
					(size 1.27 1.27)
				)
				(hide yes)
			)
		)
		(property "Description" ""
			(at 254 199.39 0)
			(effects
				(font
					(size 1.27 1.27)
				)
				(hide yes)
			)
		)
		(pin "1"
		)
		(instances
			(project "gmsl-serializer"
				(path ""
					(reference "#PWR020")
					(unit 1)
				)
			)
		)
	)
	(symbol
		(lib_id "antmicropower:+3V3")
		(at 350.52 193.04 0)
		(unit 1)
		(exclude_from_sim no)
		(in_bom yes)
		(on_board yes)
		(dnp no)
		(property "Reference" "#PWR021"
			(at 365.76 195.58 0)
			(effects
				(font
					(size 1.27 1.27)
					(thickness 0.15)
				)
				(justify left bottom)
				(hide yes)
			)
		)
		(property "Value" "+3V3"
			(at 350.52 189.23 0)
			(effects
				(font
					(size 1.27 1.27)
					(thickness 0.15)
				)
			)
		)
		(property "Footprint" ""
			(at 365.76 200.66 0)
			(effects
				(font
					(size 1.27 1.27)
					(thickness 0.15)
				)
				(justify left bottom)
				(hide yes)
			)
		)
		(property "Datasheet" ""
			(at 365.76 203.2 0)
			(effects
				(font
					(size 1.27 1.27)
					(thickness 0.15)
				)
				(justify left bottom)
				(hide yes)
			)
		)
		(property "Description" ""
			(at 350.52 193.04 0)
			(effects
				(font
					(size 1.27 1.27)
				)
				(hide yes)
			)
		)
		(property "Author" "Antmicro"
			(at 365.76 200.66 0)
			(effects
				(font
					(size 1.27 1.27)
					(thickness 0.15)
				)
				(justify left bottom)
				(hide yes)
			)
		)
		(property "License" "Apache-2.0"
			(at 365.76 203.2 0)
			(effects
				(font
					(size 1.27 1.27)
					(thickness 0.15)
				)
				(justify left bottom)
				(hide yes)
			)
		)
		(pin "1"
		)
		(instances
			(project "gmsl-serializer"
				(path ""
					(reference "#PWR021")
					(unit 1)
				)
			)
		)
	)
	(symbol
		(lib_id "antmicroResistors0402:R_10k_0402")
		(at 273.05 199.39 90)
		(unit 1)
		(exclude_from_sim no)
		(in_bom yes)
		(on_board yes)
		(dnp no)
		(fields_autoplaced yes)
		(property "Reference" "R41"
			(at 274.955 195.5799 90)
			(effects
				(font
					(size 1.27 1.27)
					(thickness 0.15)
				)
				(justify right)
			)
		)
		(property "Value" "R_10k_0402"
			(at 285.75 179.07 0)
			(effects
				(font
					(size 1.27 1.27)
					(thickness 0.15)
				)
				(justify left bottom)
				(hide yes)
			)
		)
		(property "Footprint" "antmicro-footprints:R_0402_1005Metric"
			(at 288.29 179.07 0)
			(effects
				(font
					(size 1.27 1.27)
					(thickness 0.15)
				)
				(justify left bottom)
				(hide yes)
			)
		)
		(property "Datasheet" "https://www.bourns.com/docs/product-datasheets/cr.pdf"
			(at 290.83 179.07 0)
			(effects
				(font
					(size 1.27 1.27)
					(thickness 0.15)
				)
				(justify left bottom)
				(hide yes)
			)
		)
		(property "Description" ""
			(at 273.05 199.39 0)
			(effects
				(font
					(size 1.27 1.27)
				)
				(hide yes)
			)
		)
		(property "MPN" "CR0402-FX-1002GLF"
			(at 293.37 179.07 0)
			(effects
				(font
					(size 1.27 1.27)
					(thickness 0.15)
				)
				(justify left bottom)
				(hide yes)
			)
		)
		(property "Manufacturer" "Bourns"
			(at 295.91 179.07 0)
			(effects
				(font
					(size 1.27 1.27)
					(thickness 0.15)
				)
				(justify left bottom)
				(hide yes)
			)
		)
		(property "License" "Apache-2.0"
			(at 298.45 179.07 0)
			(effects
				(font
					(size 1.27 1.27)
					(thickness 0.15)
				)
				(justify left bottom)
				(hide yes)
			)
		)
		(property "Author" "Antmicro"
			(at 300.99 179.07 0)
			(effects
				(font
					(size 1.27 1.27)
					(thickness 0.15)
				)
				(justify left bottom)
				(hide yes)
			)
		)
		(property "Val" "10k"
			(at 274.955 198.1199 90)
			(effects
				(font
					(size 1.27 1.27)
					(thickness 0.15)
				)
				(justify right)
			)
		)
		(property "Tolerance" "1%"
			(at 283.21 179.07 0)
			(effects
				(font
					(size 1.27 1.27)
				)
				(justify left bottom)
				(hide yes)
			)
		)
		(pin "1"
		)
		(pin "2"
		)
		(instances
			(project "gmsl-serializer"
				(path ""
					(reference "R41")
					(unit 1)
				)
			)
		)
	)
	(symbol
		(lib_id "antmicroFixedInductors:L_1u_2.6A_0806")
		(at 111.76 204.47 0)
		(unit 1)
		(exclude_from_sim no)
		(in_bom yes)
		(on_board yes)
		(dnp no)
		(fields_autoplaced yes)
		(property "Reference" "L2"
			(at 114.3 198.755 0)
			(effects
				(font
					(size 1.27 1.27)
					(thickness 0.15)
				)
			)
		)
		(property "Value" "L_1u_2.6A_0806"
			(at 125.73 207.01 0)
			(effects
				(font
					(size 1.27 1.27)
					(thickness 0.15)
				)
				(justify left bottom)
				(hide yes)
			)
		)
		(property "Footprint" "antmicro-footprints:L_0806_2016Metric"
			(at 125.73 212.09 0)
			(effects
				(font
					(size 1.27 1.27)
					(thickness 0.15)
				)
				(justify left bottom)
				(hide yes)
			)
		)
		(property "Datasheet" "https://www.bourns.com/docs/Product-Datasheets/SRP2010.pdf"
			(at 125.73 214.63 0)
			(effects
				(font
					(size 1.27 1.27)
					(thickness 0.15)
				)
				(justify left bottom)
				(hide yes)
			)
		)
		(property "Description" ""
			(at 111.76 204.47 0)
			(effects
				(font
					(size 1.27 1.27)
				)
				(hide yes)
			)
		)
		(property "Val" "1u/2.6A"
			(at 114.3 201.295 0)
			(effects
				(font
					(size 1.27 1.27)
					(thickness 0.15)
				)
			)
		)
		(property "Manufacturer" "Bourns"
			(at 125.73 217.17 0)
			(effects
				(font
					(size 1.27 1.27)
					(thickness 0.15)
				)
				(justify left bottom)
				(hide yes)
			)
		)
		(property "MPN" "SRP2010-1R0M"
			(at 125.73 219.71 0)
			(effects
				(font
					(size 1.27 1.27)
					(thickness 0.15)
				)
				(justify left bottom)
				(hide yes)
			)
		)
		(property "ISat" "2.9 A"
			(at 125.73 220.98 0)
			(effects
				(font
					(size 1.27 1.27)
				)
				(justify left)
				(hide yes)
			)
		)
		(property "IMax" "2.6 A"
			(at 125.73 224.79 0)
			(effects
				(font
					(size 1.27 1.27)
					(thickness 0.15)
				)
				(justify left bottom)
				(hide yes)
			)
		)
		(property "Size" "2.0x1.6"
			(at 125.73 227.33 0)
			(effects
				(font
					(size 1.27 1.27)
					(thickness 0.15)
				)
				(justify left bottom)
				(hide yes)
			)
		)
		(property "Author" "Antmicro"
			(at 125.73 229.87 0)
			(effects
				(font
					(size 1.27 1.27)
					(thickness 0.15)
				)
				(justify left bottom)
				(hide yes)
			)
		)
		(property "License" "Apache-2.0"
			(at 125.73 232.41 0)
			(effects
				(font
					(size 1.27 1.27)
					(thickness 0.15)
				)
				(justify left bottom)
				(hide yes)
			)
		)
		(pin "1"
		)
		(pin "2"
		)
		(instances
			(project "gmsl-serializer"
				(path ""
					(reference "L2")
					(unit 1)
				)
			)
		)
	)
	(symbol
		(lib_id "antmicroResistors0402:R_31k6_0402")
		(at 321.31 208.28 90)
		(unit 1)
		(exclude_from_sim no)
		(in_bom yes)
		(on_board yes)
		(dnp no)
		(fields_autoplaced yes)
		(property "Reference" "R37"
			(at 323.85 204.47 90)
			(effects
				(font
					(size 1.27 1.27)
					(thickness 0.15)
				)
				(justify right)
			)
		)
		(property "Value" "R_31k6_0402"
			(at 334.01 187.96 0)
			(effects
				(font
					(size 1.27 1.27)
					(thickness 0.15)
				)
				(justify left bottom)
				(hide yes)
			)
		)
		(property "Footprint" "antmicro-footprints:R_0402_1005Metric"
			(at 336.55 187.96 0)
			(effects
				(font
					(size 1.27 1.27)
					(thickness 0.15)
				)
				(justify left bottom)
				(hide yes)
			)
		)
		(property "Datasheet" "https://www.bourns.com/docs/product-datasheets/cr.pdf"
			(at 339.09 187.96 0)
			(effects
				(font
					(size 1.27 1.27)
					(thickness 0.15)
				)
				(justify left bottom)
				(hide yes)
			)
		)
		(property "Description" "SMD Chip Resistor"
			(at 321.31 208.28 0)
			(effects
				(font
					(size 1.27 1.27)
				)
				(hide yes)
			)
		)
		(property "MPN" "CR0402-FX-3162GLF"
			(at 341.63 187.96 0)
			(effects
				(font
					(size 1.27 1.27)
					(thickness 0.15)
				)
				(justify left bottom)
				(hide yes)
			)
		)
		(property "Manufacturer" "Bourns"
			(at 344.17 187.96 0)
			(effects
				(font
					(size 1.27 1.27)
					(thickness 0.15)
				)
				(justify left bottom)
				(hide yes)
			)
		)
		(property "License" "Apache-2.0"
			(at 346.71 187.96 0)
			(effects
				(font
					(size 1.27 1.27)
					(thickness 0.15)
				)
				(justify left bottom)
				(hide yes)
			)
		)
		(property "Author" "Antmicro"
			(at 349.25 187.96 0)
			(effects
				(font
					(size 1.27 1.27)
					(thickness 0.15)
				)
				(justify left bottom)
				(hide yes)
			)
		)
		(property "Val" "31k6"
			(at 323.85 207.01 90)
			(effects
				(font
					(size 1.27 1.27)
					(thickness 0.15)
				)
				(justify right)
			)
		)
		(property "Tolerance" "1%"
			(at 331.47 187.96 0)
			(effects
				(font
					(size 1.27 1.27)
				)
				(justify left bottom)
				(hide yes)
			)
		)
		(pin "2"
		)
		(pin "1"
		)
		(instances
			(project ""
				(path ""
					(reference "R37")
					(unit 1)
				)
			)
		)
	)
	(symbol
		(lib_id "antmicroLEDIndicationDiscrete:LED_G_0603_LTST-C190GKT")
		(at 351.79 120.65 270)
		(mirror x)
		(unit 1)
		(exclude_from_sim no)
		(in_bom yes)
		(on_board yes)
		(dnp no)
		(property "Reference" "D6"
			(at 355.6 116.84 90)
			(effects
				(font
					(size 1.27 1.27)
					(thickness 0.15)
				)
				(justify left)
			)
		)
		(property "Value" "LED_G_0603_LTST-C190GKT"
			(at 323.215 115.57 90)
			(effects
				(font
					(size 1.27 1.27)
					(thickness 0.15)
				)
				(justify left)
				(hide yes)
			)
		)
		(property "Footprint" "antmicro-footprints:LED_0603_1608Metric_G"
			(at 341.63 97.79 0)
			(effects
				(font
					(size 1.27 1.27)
					(thickness 0.15)
				)
				(justify left bottom)
				(hide yes)
			)
		)
		(property "Datasheet" "https://media.digikey.com/pdf/Data%20Sheets/Lite-On%20PDFs/LTST-C190GKT.pdf"
			(at 339.09 97.79 0)
			(effects
				(font
					(size 1.27 1.27)
					(thickness 0.15)
				)
				(justify left bottom)
				(hide yes)
			)
		)
		(property "Description" ""
			(at 351.79 120.65 0)
			(effects
				(font
					(size 1.27 1.27)
				)
				(hide yes)
			)
		)
		(property "MPN" "LTST-C190GKT"
			(at 355.6 118.11 90)
			(effects
				(font
					(size 1.27 1.27)
					(thickness 0.15)
				)
				(justify left bottom)
			)
		)
		(property "Manufacturer" "Lite-On"
			(at 334.01 97.79 0)
			(effects
				(font
					(size 1.27 1.27)
					(thickness 0.15)
				)
				(justify left bottom)
				(hide yes)
			)
		)
		(property "Author" "Antmicro"
			(at 331.47 97.79 0)
			(effects
				(font
					(size 1.27 1.27)
					(thickness 0.15)
				)
				(justify left bottom)
				(hide yes)
			)
		)
		(property "License" "Apache-2.0"
			(at 328.93 97.79 0)
			(effects
				(font
					(size 1.27 1.27)
					(thickness 0.15)
				)
				(justify left bottom)
				(hide yes)
			)
		)
		(property "VSD_class" "LED"
			(at 326.39 97.79 0)
			(effects
				(font
					(size 1.27 1.27)
				)
				(justify left bottom)
				(hide yes)
			)
		)
		(property "Color" "Green"
			(at 346.71 97.79 0)
			(effects
				(font
					(size 1.27 1.27)
				)
				(justify left bottom)
				(hide yes)
			)
		)
		(pin "1"
		)
		(pin "2"
		)
		(instances
			(project "gmsl-serializer"
				(path ""
					(reference "D6")
					(unit 1)
				)
			)
		)
	)
	(symbol
		(lib_id "antmicroResistors0402:R_52k3_0402")
		(at 135.89 87.63 90)
		(unit 1)
		(exclude_from_sim no)
		(in_bom yes)
		(on_board yes)
		(dnp no)
		(fields_autoplaced yes)
		(property "Reference" "R9"
			(at 138.43 83.8199 90)
			(effects
				(font
					(size 1.27 1.27)
					(thickness 0.15)
				)
				(justify right)
			)
		)
		(property "Value" "R_52k3_0402"
			(at 148.59 67.31 0)
			(effects
				(font
					(size 1.27 1.27)
					(thickness 0.15)
				)
				(justify left bottom)
				(hide yes)
			)
		)
		(property "Footprint" "antmicro-footprints:R_0402_1005Metric"
			(at 151.13 67.31 0)
			(effects
				(font
					(size 1.27 1.27)
					(thickness 0.15)
				)
				(justify left bottom)
				(hide yes)
			)
		)
		(property "Datasheet" "https://www.bourns.com/docs/product-datasheets/cr.pdf"
			(at 153.67 67.31 0)
			(effects
				(font
					(size 1.27 1.27)
					(thickness 0.15)
				)
				(justify left bottom)
				(hide yes)
			)
		)
		(property "Description" ""
			(at 135.89 87.63 0)
			(effects
				(font
					(size 1.27 1.27)
				)
				(hide yes)
			)
		)
		(property "MPN" "CR0402-FX-5232GLF"
			(at 156.21 67.31 0)
			(effects
				(font
					(size 1.27 1.27)
					(thickness 0.15)
				)
				(justify left bottom)
				(hide yes)
			)
		)
		(property "Manufacturer" "Bourns"
			(at 158.75 67.31 0)
			(effects
				(font
					(size 1.27 1.27)
					(thickness 0.15)
				)
				(justify left bottom)
				(hide yes)
			)
		)
		(property "License" "Apache-2.0"
			(at 161.29 67.31 0)
			(effects
				(font
					(size 1.27 1.27)
					(thickness 0.15)
				)
				(justify left bottom)
				(hide yes)
			)
		)
		(property "Author" "Antmicro"
			(at 163.83 67.31 0)
			(effects
				(font
					(size 1.27 1.27)
					(thickness 0.15)
				)
				(justify left bottom)
				(hide yes)
			)
		)
		(property "Val" "52k3"
			(at 138.43 86.3599 90)
			(effects
				(font
					(size 1.27 1.27)
					(thickness 0.15)
				)
				(justify right)
			)
		)
		(property "Tolerance" "1%"
			(at 146.05 67.31 0)
			(effects
				(font
					(size 1.27 1.27)
				)
				(justify left bottom)
				(hide yes)
			)
		)
		(pin "1"
		)
		(pin "2"
		)
		(instances
			(project "gmsl-serializer"
				(path ""
					(reference "R9")
					(unit 1)
				)
			)
		)
	)
	(symbol
		(lib_id "antmicroDCDCConverters:AP62301_TSOT")
		(at 96.52 81.28 0)
		(unit 1)
		(exclude_from_sim no)
		(in_bom yes)
		(on_board yes)
		(dnp no)
		(fields_autoplaced yes)
		(property "Reference" "U1"
			(at 106.68 73.025 0)
			(effects
				(font
					(size 1.27 1.27)
					(thickness 0.15)
				)
			)
		)
		(property "Value" "AP62301_TSOT"
			(at 132.08 88.9 0)
			(effects
				(font
					(size 1.27 1.27)
					(thickness 0.15)
				)
				(justify left bottom)
				(hide yes)
			)
		)
		(property "Footprint" "antmicro-footprints:TSOT23-6"
			(at 132.08 91.44 0)
			(effects
				(font
					(size 1.27 1.27)
					(thickness 0.15)
				)
				(justify left bottom)
				(hide yes)
			)
		)
		(property "Datasheet" "https://www.diodes.com/assets/Datasheets/AP62300_AP62301_AP62300T.pdf"
			(at 132.08 93.98 0)
			(effects
				(font
					(size 1.27 1.27)
					(thickness 0.15)
				)
				(justify left bottom)
				(hide yes)
			)
		)
		(property "Description" ""
			(at 96.52 81.28 0)
			(effects
				(font
					(size 1.27 1.27)
				)
				(hide yes)
			)
		)
		(property "MPN" "AP62301WU-7"
			(at 106.68 75.565 0)
			(effects
				(font
					(size 1.27 1.27)
					(thickness 0.15)
				)
			)
		)
		(property "Manufacturer" "Diodes Incorporated"
			(at 132.08 96.52 0)
			(effects
				(font
					(size 1.27 1.27)
					(thickness 0.15)
				)
				(justify left bottom)
				(hide yes)
			)
		)
		(property "Author" "Antmicro"
			(at 132.08 99.06 0)
			(effects
				(font
					(size 1.27 1.27)
					(thickness 0.15)
				)
				(justify left bottom)
				(hide yes)
			)
		)
		(property "License" "Apache-2.0"
			(at 132.08 101.6 0)
			(effects
				(font
					(size 1.27 1.27)
					(thickness 0.15)
				)
				(justify left bottom)
				(hide yes)
			)
		)
		(pin "1"
		)
		(pin "2"
		)
		(pin "3"
		)
		(pin "4"
		)
		(pin "5"
		)
		(pin "6"
		)
		(instances
			(project "gmsl-serializer"
				(path ""
					(reference "U1")
					(unit 1)
				)
			)
		)
	)
	(symbol
		(lib_id "antmicropower:GND")
		(at 292.1 62.23 0)
		(mirror y)
		(unit 1)
		(exclude_from_sim no)
		(in_bom yes)
		(on_board yes)
		(dnp no)
		(property "Reference" "#PWR0108"
			(at 283.21 64.77 0)
			(effects
				(font
					(size 1.27 1.27)
					(thickness 0.15)
				)
				(justify left bottom)
				(hide yes)
			)
		)
		(property "Value" "GND"
			(at 292.1 66.04 0)
			(effects
				(font
					(size 1.27 1.27)
					(thickness 0.15)
				)
			)
		)
		(property "Footprint" ""
			(at 283.21 69.85 0)
			(effects
				(font
					(size 1.27 1.27)
					(thickness 0.15)
				)
				(justify left bottom)
				(hide yes)
			)
		)
		(property "Datasheet" ""
			(at 283.21 74.93 0)
			(effects
				(font
					(size 1.27 1.27)
					(thickness 0.15)
				)
				(justify left bottom)
				(hide yes)
			)
		)
		(property "Description" ""
			(at 292.1 62.23 0)
			(effects
				(font
					(size 1.27 1.27)
				)
				(hide yes)
			)
		)
		(property "Author" "Antmicro"
			(at 283.21 69.85 0)
			(effects
				(font
					(size 1.27 1.27)
					(thickness 0.15)
				)
				(justify left bottom)
				(hide yes)
			)
		)
		(property "License" "Apache-2.0"
			(at 283.21 72.39 0)
			(effects
				(font
					(size 1.27 1.27)
					(thickness 0.15)
				)
				(justify left bottom)
				(hide yes)
			)
		)
		(pin "1"
		)
		(instances
			(project "gmsl-serializer"
				(path ""
					(reference "#PWR0108")
					(unit 1)
				)
			)
		)
	)
	(symbol
		(lib_id "antmicropower:+5V")
		(at 165.1 72.39 0)
		(unit 1)
		(exclude_from_sim no)
		(in_bom yes)
		(on_board yes)
		(dnp no)
		(property "Reference" "#PWR0132"
			(at 180.34 74.93 0)
			(effects
				(font
					(size 1.27 1.27)
					(thickness 0.15)
				)
				(justify left bottom)
				(hide yes)
			)
		)
		(property "Value" "+5V"
			(at 165.1 68.58 0)
			(effects
				(font
					(size 1.27 1.27)
					(thickness 0.15)
				)
			)
		)
		(property "Footprint" ""
			(at 180.34 80.01 0)
			(effects
				(font
					(size 1.27 1.27)
					(thickness 0.15)
				)
				(justify left bottom)
				(hide yes)
			)
		)
		(property "Datasheet" ""
			(at 180.34 82.55 0)
			(effects
				(font
					(size 1.27 1.27)
					(thickness 0.15)
				)
				(justify left bottom)
				(hide yes)
			)
		)
		(property "Description" ""
			(at 165.1 72.39 0)
			(effects
				(font
					(size 1.27 1.27)
				)
				(hide yes)
			)
		)
		(property "Author" "Antmicro"
			(at 180.34 80.01 0)
			(effects
				(font
					(size 1.27 1.27)
					(thickness 0.15)
				)
				(justify left bottom)
				(hide yes)
			)
		)
		(property "License" "Apache-2.0"
			(at 180.34 82.55 0)
			(effects
				(font
					(size 1.27 1.27)
					(thickness 0.15)
				)
				(justify left bottom)
				(hide yes)
			)
		)
		(pin "1"
		)
		(instances
			(project "gmsl-serializer"
				(path ""
					(reference "#PWR0132")
					(unit 1)
				)
			)
		)
	)
	(symbol
		(lib_id "antmicropower:GND")
		(at 300.99 135.89 0)
		(unit 1)
		(exclude_from_sim no)
		(in_bom yes)
		(on_board yes)
		(dnp no)
		(fields_autoplaced yes)
		(property "Reference" "#PWR0135"
			(at 309.88 138.43 0)
			(effects
				(font
					(size 1.27 1.27)
					(thickness 0.15)
				)
				(justify left bottom)
				(hide yes)
			)
		)
		(property "Value" "GND"
			(at 300.99 140.97 0)
			(effects
				(font
					(size 1.27 1.27)
					(thickness 0.15)
				)
			)
		)
		(property "Footprint" ""
			(at 309.88 143.51 0)
			(effects
				(font
					(size 1.27 1.27)
					(thickness 0.15)
				)
				(justify left bottom)
				(hide yes)
			)
		)
		(property "Datasheet" ""
			(at 309.88 148.59 0)
			(effects
				(font
					(size 1.27 1.27)
					(thickness 0.15)
				)
				(justify left bottom)
				(hide yes)
			)
		)
		(property "Description" ""
			(at 300.99 135.89 0)
			(effects
				(font
					(size 1.27 1.27)
				)
				(hide yes)
			)
		)
		(property "Author" "Antmicro"
			(at 309.88 143.51 0)
			(effects
				(font
					(size 1.27 1.27)
					(thickness 0.15)
				)
				(justify left bottom)
				(hide yes)
			)
		)
		(property "License" "Apache-2.0"
			(at 309.88 146.05 0)
			(effects
				(font
					(size 1.27 1.27)
					(thickness 0.15)
				)
				(justify left bottom)
				(hide yes)
			)
		)
		(pin "1"
		)
		(instances
			(project "gmsl-serializer"
				(path ""
					(reference "#PWR0135")
					(unit 1)
				)
			)
		)
	)
	(symbol
		(lib_id "antmicroCapacitors0402:C_1u_16V_0402")
		(at 270.51 134.62 90)
		(unit 1)
		(exclude_from_sim no)
		(in_bom yes)
		(on_board yes)
		(dnp no)
		(property "Reference" "C14"
			(at 260.35 130.81 90)
			(effects
				(font
					(size 1.27 1.27)
					(thickness 0.15)
				)
				(justify right)
			)
		)
		(property "Value" "C_1u_16V_0402"
			(at 280.67 114.3 0)
			(effects
				(font
					(size 1.27 1.27)
					(thickness 0.15)
				)
				(justify left bottom)
				(hide yes)
			)
		)
		(property "Footprint" "antmicro-footprints:C_0402_1005Metric"
			(at 283.21 114.3 0)
			(effects
				(font
					(size 1.27 1.27)
					(thickness 0.15)
				)
				(justify left bottom)
				(hide yes)
			)
		)
		(property "Datasheet" "https://www.kemet.com/en/us/capacitors/product/C0402C105M4PACTU.html"
			(at 285.75 114.3 0)
			(effects
				(font
					(size 1.27 1.27)
					(thickness 0.15)
				)
				(justify left bottom)
				(hide yes)
			)
		)
		(property "Description" ""
			(at 270.51 134.62 0)
			(effects
				(font
					(size 1.27 1.27)
				)
				(hide yes)
			)
		)
		(property "MPN" "C0402C105M4PACTU"
			(at 288.29 114.3 0)
			(effects
				(font
					(size 1.27 1.27)
					(thickness 0.15)
				)
				(justify left bottom)
				(hide yes)
			)
		)
		(property "Manufacturer" "KEMET"
			(at 290.83 114.3 0)
			(effects
				(font
					(size 1.27 1.27)
					(thickness 0.15)
				)
				(justify left bottom)
				(hide yes)
			)
		)
		(property "License" "Apache-2.0"
			(at 293.37 114.3 0)
			(effects
				(font
					(size 1.27 1.27)
					(thickness 0.15)
				)
				(justify left bottom)
				(hide yes)
			)
		)
		(property "Author" "Antmicro"
			(at 295.91 114.3 0)
			(effects
				(font
					(size 1.27 1.27)
					(thickness 0.15)
				)
				(justify left bottom)
				(hide yes)
			)
		)
		(property "Val" "1u"
			(at 260.35 133.35 90)
			(effects
				(font
					(size 1.27 1.27)
					(thickness 0.15)
				)
				(justify right)
			)
		)
		(property "Voltage" "16V"
			(at 298.45 114.3 0)
			(effects
				(font
					(size 1.27 1.27)
				)
				(justify left bottom)
				(hide yes)
			)
		)
		(property "Dielectric" ""
			(at 300.99 114.3 0)
			(effects
				(font
					(size 1.27 1.27)
				)
				(justify left bottom)
				(hide yes)
			)
		)
		(pin "1"
		)
		(pin "2"
		)
		(instances
			(project "gmsl-serializer"
				(path ""
					(reference "C14")
					(unit 1)
				)
			)
		)
	)
	(symbol
		(lib_id "antmicroResistors0402:R_10k_0402")
		(at 87.63 78.74 90)
		(unit 1)
		(exclude_from_sim no)
		(in_bom yes)
		(on_board yes)
		(dnp no)
		(fields_autoplaced yes)
		(property "Reference" "R7"
			(at 89.535 74.9299 90)
			(effects
				(font
					(size 1.27 1.27)
					(thickness 0.15)
				)
				(justify right)
			)
		)
		(property "Value" "R_10k_0402"
			(at 100.33 58.42 0)
			(effects
				(font
					(size 1.27 1.27)
					(thickness 0.15)
				)
				(justify left bottom)
				(hide yes)
			)
		)
		(property "Footprint" "antmicro-footprints:R_0402_1005Metric"
			(at 102.87 58.42 0)
			(effects
				(font
					(size 1.27 1.27)
					(thickness 0.15)
				)
				(justify left bottom)
				(hide yes)
			)
		)
		(property "Datasheet" "https://www.bourns.com/docs/product-datasheets/cr.pdf"
			(at 105.41 58.42 0)
			(effects
				(font
					(size 1.27 1.27)
					(thickness 0.15)
				)
				(justify left bottom)
				(hide yes)
			)
		)
		(property "Description" ""
			(at 87.63 78.74 0)
			(effects
				(font
					(size 1.27 1.27)
				)
				(hide yes)
			)
		)
		(property "MPN" "CR0402-FX-1002GLF"
			(at 107.95 58.42 0)
			(effects
				(font
					(size 1.27 1.27)
					(thickness 0.15)
				)
				(justify left bottom)
				(hide yes)
			)
		)
		(property "Manufacturer" "Bourns"
			(at 110.49 58.42 0)
			(effects
				(font
					(size 1.27 1.27)
					(thickness 0.15)
				)
				(justify left bottom)
				(hide yes)
			)
		)
		(property "License" "Apache-2.0"
			(at 113.03 58.42 0)
			(effects
				(font
					(size 1.27 1.27)
					(thickness 0.15)
				)
				(justify left bottom)
				(hide yes)
			)
		)
		(property "Author" "Antmicro"
			(at 115.57 58.42 0)
			(effects
				(font
					(size 1.27 1.27)
					(thickness 0.15)
				)
				(justify left bottom)
				(hide yes)
			)
		)
		(property "Val" "10k"
			(at 89.535 77.4699 90)
			(effects
				(font
					(size 1.27 1.27)
					(thickness 0.15)
				)
				(justify right)
			)
		)
		(property "Tolerance" "1%"
			(at 97.79 58.42 0)
			(effects
				(font
					(size 1.27 1.27)
				)
				(justify left bottom)
				(hide yes)
			)
		)
		(pin "1"
		)
		(pin "2"
		)
		(instances
			(project "gmsl-serializer"
				(path ""
					(reference "R7")
					(unit 1)
				)
			)
		)
	)
	(symbol
		(lib_id "antmicroCapacitors0402:C_100n_0402")
		(at 101.6 209.55 0)
		(unit 1)
		(exclude_from_sim no)
		(in_bom yes)
		(on_board yes)
		(dnp no)
		(property "Reference" "C4"
			(at 106.68 208.28 0)
			(effects
				(font
					(size 1.27 1.27)
					(thickness 0.15)
				)
			)
		)
		(property "Value" "C_100n_0402"
			(at 121.92 219.71 0)
			(effects
				(font
					(size 1.27 1.27)
					(thickness 0.15)
				)
				(justify left bottom)
				(hide yes)
			)
		)
		(property "Footprint" "antmicro-footprints:C_0402_1005Metric"
			(at 121.92 222.25 0)
			(effects
				(font
					(size 1.27 1.27)
					(thickness 0.15)
				)
				(justify left bottom)
				(hide yes)
			)
		)
		(property "Datasheet" "https://www.murata.com/products/productdetail?partno=GRM155R61H104KE14%23"
			(at 121.92 224.79 0)
			(effects
				(font
					(size 1.27 1.27)
					(thickness 0.15)
				)
				(justify left bottom)
				(hide yes)
			)
		)
		(property "Description" ""
			(at 101.6 209.55 0)
			(effects
				(font
					(size 1.27 1.27)
				)
				(hide yes)
			)
		)
		(property "MPN" "GRM155R61H104KE14D"
			(at 121.92 227.33 0)
			(effects
				(font
					(size 1.27 1.27)
					(thickness 0.15)
				)
				(justify left bottom)
				(hide yes)
			)
		)
		(property "Manufacturer" "Murata"
			(at 121.92 229.87 0)
			(effects
				(font
					(size 1.27 1.27)
					(thickness 0.15)
				)
				(justify left bottom)
				(hide yes)
			)
		)
		(property "License" "Apache-2.0"
			(at 121.92 232.41 0)
			(effects
				(font
					(size 1.27 1.27)
					(thickness 0.15)
				)
				(justify left bottom)
				(hide yes)
			)
		)
		(property "Author" "Antmicro"
			(at 121.92 234.95 0)
			(effects
				(font
					(size 1.27 1.27)
					(thickness 0.15)
				)
				(justify left bottom)
				(hide yes)
			)
		)
		(property "Val" "100n"
			(at 107.95 210.82 0)
			(effects
				(font
					(size 1.27 1.27)
					(thickness 0.15)
				)
			)
		)
		(property "Voltage" "50V"
			(at 121.92 237.49 0)
			(effects
				(font
					(size 1.27 1.27)
				)
				(justify left bottom)
				(hide yes)
			)
		)
		(property "Dielectric" "X5R"
			(at 121.92 240.03 0)
			(effects
				(font
					(size 1.27 1.27)
				)
				(justify left bottom)
				(hide yes)
			)
		)
		(pin "1"
		)
		(pin "2"
		)
		(instances
			(project "gmsl-serializer"
				(path ""
					(reference "C4")
					(unit 1)
				)
			)
		)
	)
	(symbol
		(lib_id "antmicropower:GND")
		(at 77.47 217.17 0)
		(unit 1)
		(exclude_from_sim no)
		(in_bom yes)
		(on_board yes)
		(dnp no)
		(property "Reference" "#PWR0110"
			(at 86.36 219.71 0)
			(effects
				(font
					(size 1.27 1.27)
					(thickness 0.15)
				)
				(justify left bottom)
				(hide yes)
			)
		)
		(property "Value" "GND"
			(at 77.47 220.98 0)
			(effects
				(font
					(size 1.27 1.27)
					(thickness 0.15)
				)
			)
		)
		(property "Footprint" ""
			(at 86.36 224.79 0)
			(effects
				(font
					(size 1.27 1.27)
					(thickness 0.15)
				)
				(justify left bottom)
				(hide yes)
			)
		)
		(property "Datasheet" ""
			(at 86.36 229.87 0)
			(effects
				(font
					(size 1.27 1.27)
					(thickness 0.15)
				)
				(justify left bottom)
				(hide yes)
			)
		)
		(property "Description" ""
			(at 77.47 217.17 0)
			(effects
				(font
					(size 1.27 1.27)
				)
				(hide yes)
			)
		)
		(property "Author" "Antmicro"
			(at 86.36 224.79 0)
			(effects
				(font
					(size 1.27 1.27)
					(thickness 0.15)
				)
				(justify left bottom)
				(hide yes)
			)
		)
		(property "License" "Apache-2.0"
			(at 86.36 227.33 0)
			(effects
				(font
					(size 1.27 1.27)
					(thickness 0.15)
				)
				(justify left bottom)
				(hide yes)
			)
		)
		(pin "1"
		)
		(instances
			(project "gmsl-serializer"
				(path ""
					(reference "#PWR0110")
					(unit 1)
				)
			)
		)
	)
	(symbol
		(lib_id "antmicropower:+1V2")
		(at 339.09 128.27 0)
		(unit 1)
		(exclude_from_sim no)
		(in_bom yes)
		(on_board yes)
		(dnp no)
		(fields_autoplaced yes)
		(property "Reference" "#PWR016"
			(at 339.09 132.08 0)
			(effects
				(font
					(size 1.27 1.27)
				)
				(hide yes)
			)
		)
		(property "Value" "+1V2"
			(at 339.09 123.19 0)
			(effects
				(font
					(size 1.27 1.27)
				)
			)
		)
		(property "Footprint" ""
			(at 339.09 128.27 0)
			(effects
				(font
					(size 1.27 1.27)
				)
				(hide yes)
			)
		)
		(property "Datasheet" ""
			(at 339.09 128.27 0)
			(effects
				(font
					(size 1.27 1.27)
				)
				(hide yes)
			)
		)
		(property "Description" ""
			(at 339.09 128.27 0)
			(effects
				(font
					(size 1.27 1.27)
				)
				(hide yes)
			)
		)
		(pin "1"
		)
		(instances
			(project "gmsl-serializer"
				(path ""
					(reference "#PWR016")
					(unit 1)
				)
			)
		)
	)
	(symbol
		(lib_id "antmicropower:GND")
		(at 76.2 92.71 0)
		(unit 1)
		(exclude_from_sim no)
		(in_bom yes)
		(on_board yes)
		(dnp no)
		(property "Reference" "#PWR0123"
			(at 85.09 95.25 0)
			(effects
				(font
					(size 1.27 1.27)
					(thickness 0.15)
				)
				(justify left bottom)
				(hide yes)
			)
		)
		(property "Value" "GND"
			(at 76.2 96.52 0)
			(effects
				(font
					(size 1.27 1.27)
					(thickness 0.15)
				)
			)
		)
		(property "Footprint" ""
			(at 85.09 100.33 0)
			(effects
				(font
					(size 1.27 1.27)
					(thickness 0.15)
				)
				(justify left bottom)
				(hide yes)
			)
		)
		(property "Datasheet" ""
			(at 85.09 105.41 0)
			(effects
				(font
					(size 1.27 1.27)
					(thickness 0.15)
				)
				(justify left bottom)
				(hide yes)
			)
		)
		(property "Description" ""
			(at 76.2 92.71 0)
			(effects
				(font
					(size 1.27 1.27)
				)
				(hide yes)
			)
		)
		(property "Author" "Antmicro"
			(at 85.09 100.33 0)
			(effects
				(font
					(size 1.27 1.27)
					(thickness 0.15)
				)
				(justify left bottom)
				(hide yes)
			)
		)
		(property "License" "Apache-2.0"
			(at 85.09 102.87 0)
			(effects
				(font
					(size 1.27 1.27)
					(thickness 0.15)
				)
				(justify left bottom)
				(hide yes)
			)
		)
		(pin "1"
		)
		(instances
			(project "gmsl-serializer"
				(path ""
					(reference "#PWR0123")
					(unit 1)
				)
			)
		)
	)
	(symbol
		(lib_id "antmicroResistors0402:R_100k_0402")
		(at 158.75 233.68 90)
		(unit 1)
		(exclude_from_sim no)
		(in_bom yes)
		(on_board yes)
		(dnp no)
		(fields_autoplaced yes)
		(property "Reference" "R38"
			(at 161.29 229.8699 90)
			(effects
				(font
					(size 1.27 1.27)
					(thickness 0.15)
				)
				(justify right)
			)
		)
		(property "Value" "R_100k_0402"
			(at 171.45 213.36 0)
			(effects
				(font
					(size 1.27 1.27)
					(thickness 0.15)
				)
				(justify left bottom)
				(hide yes)
			)
		)
		(property "Footprint" "antmicro-footprints:R_0402_1005Metric"
			(at 173.99 213.36 0)
			(effects
				(font
					(size 1.27 1.27)
					(thickness 0.15)
				)
				(justify left bottom)
				(hide yes)
			)
		)
		(property "Datasheet" "https://www.bourns.com/docs/product-datasheets/cr.pdf"
			(at 176.53 213.36 0)
			(effects
				(font
					(size 1.27 1.27)
					(thickness 0.15)
				)
				(justify left bottom)
				(hide yes)
			)
		)
		(property "Description" ""
			(at 158.75 233.68 0)
			(effects
				(font
					(size 1.27 1.27)
				)
				(hide yes)
			)
		)
		(property "MPN" "CR0402-FX-1003GLF"
			(at 179.07 213.36 0)
			(effects
				(font
					(size 1.27 1.27)
					(thickness 0.15)
				)
				(justify left bottom)
				(hide yes)
			)
		)
		(property "Manufacturer" "Bourns"
			(at 181.61 213.36 0)
			(effects
				(font
					(size 1.27 1.27)
					(thickness 0.15)
				)
				(justify left bottom)
				(hide yes)
			)
		)
		(property "License" "Apache-2.0"
			(at 184.15 213.36 0)
			(effects
				(font
					(size 1.27 1.27)
					(thickness 0.15)
				)
				(justify left bottom)
				(hide yes)
			)
		)
		(property "Author" "Antmicro"
			(at 186.69 213.36 0)
			(effects
				(font
					(size 1.27 1.27)
					(thickness 0.15)
				)
				(justify left bottom)
				(hide yes)
			)
		)
		(property "Val" "100k"
			(at 161.29 232.4099 90)
			(effects
				(font
					(size 1.27 1.27)
					(thickness 0.15)
				)
				(justify right)
			)
		)
		(property "Tolerance" "1%"
			(at 168.91 213.36 0)
			(effects
				(font
					(size 1.27 1.27)
				)
				(justify left bottom)
				(hide yes)
			)
		)
		(pin "1"
		)
		(pin "2"
		)
		(instances
			(project "gmsl-serializer"
				(path ""
					(reference "R38")
					(unit 1)
				)
			)
		)
	)
	(symbol
		(lib_id "antmicroLEDIndicationDiscrete:LED_G_0603_LTST-C190GKT")
		(at 165.1 91.44 270)
		(mirror x)
		(unit 1)
		(exclude_from_sim no)
		(in_bom yes)
		(on_board yes)
		(dnp no)
		(property "Reference" "D5"
			(at 168.91 87.63 90)
			(effects
				(font
					(size 1.27 1.27)
					(thickness 0.15)
				)
				(justify left)
			)
		)
		(property "Value" "LED_G_0603_LTST-C190GKT"
			(at 136.525 86.36 90)
			(effects
				(font
					(size 1.27 1.27)
					(thickness 0.15)
				)
				(justify left)
				(hide yes)
			)
		)
		(property "Footprint" "antmicro-footprints:LED_0603_1608Metric_G"
			(at 154.94 68.58 0)
			(effects
				(font
					(size 1.27 1.27)
					(thickness 0.15)
				)
				(justify left bottom)
				(hide yes)
			)
		)
		(property "Datasheet" "https://media.digikey.com/pdf/Data%20Sheets/Lite-On%20PDFs/LTST-C190GKT.pdf"
			(at 152.4 68.58 0)
			(effects
				(font
					(size 1.27 1.27)
					(thickness 0.15)
				)
				(justify left bottom)
				(hide yes)
			)
		)
		(property "Description" ""
			(at 165.1 91.44 0)
			(effects
				(font
					(size 1.27 1.27)
				)
				(hide yes)
			)
		)
		(property "MPN" "LTST-C190GKT"
			(at 168.91 88.9 90)
			(effects
				(font
					(size 1.27 1.27)
					(thickness 0.15)
				)
				(justify left bottom)
			)
		)
		(property "Manufacturer" "Lite-On"
			(at 147.32 68.58 0)
			(effects
				(font
					(size 1.27 1.27)
					(thickness 0.15)
				)
				(justify left bottom)
				(hide yes)
			)
		)
		(property "Author" "Antmicro"
			(at 144.78 68.58 0)
			(effects
				(font
					(size 1.27 1.27)
					(thickness 0.15)
				)
				(justify left bottom)
				(hide yes)
			)
		)
		(property "License" "Apache-2.0"
			(at 142.24 68.58 0)
			(effects
				(font
					(size 1.27 1.27)
					(thickness 0.15)
				)
				(justify left bottom)
				(hide yes)
			)
		)
		(property "VSD_class" "LED"
			(at 139.7 68.58 0)
			(effects
				(font
					(size 1.27 1.27)
				)
				(justify left bottom)
				(hide yes)
			)
		)
		(property "Color" "Green"
			(at 160.02 68.58 0)
			(effects
				(font
					(size 1.27 1.27)
				)
				(justify left bottom)
				(hide yes)
			)
		)
		(pin "1"
		)
		(pin "2"
		)
		(instances
			(project "gmsl-serializer"
				(path ""
					(reference "D5")
					(unit 1)
				)
			)
		)
	)
	(symbol
		(lib_id "antmicropower:+12V")
		(at 71.12 194.31 0)
		(unit 1)
		(exclude_from_sim no)
		(in_bom yes)
		(on_board yes)
		(dnp no)
		(fields_autoplaced yes)
		(property "Reference" "#PWR0125"
			(at 71.12 198.12 0)
			(effects
				(font
					(size 1.27 1.27)
				)
				(hide yes)
			)
		)
		(property "Value" "+12V"
			(at 71.12 189.23 0)
			(effects
				(font
					(size 1.27 1.27)
				)
			)
		)
		(property "Footprint" ""
			(at 71.12 194.31 0)
			(effects
				(font
					(size 1.27 1.27)
				)
				(hide yes)
			)
		)
		(property "Datasheet" ""
			(at 71.12 194.31 0)
			(effects
				(font
					(size 1.27 1.27)
				)
				(hide yes)
			)
		)
		(property "Description" ""
			(at 71.12 194.31 0)
			(effects
				(font
					(size 1.27 1.27)
				)
				(hide yes)
			)
		)
		(pin "1"
		)
		(instances
			(project "gmsl-serializer"
				(path ""
					(reference "#PWR0125")
					(unit 1)
				)
			)
		)
	)
	(symbol
		(lib_id "antmicroFixedInductors:L_3u3_3.1A_Bourns-SRP3212A")
		(at 313.69 201.93 0)
		(unit 1)
		(exclude_from_sim no)
		(in_bom yes)
		(on_board yes)
		(dnp no)
		(fields_autoplaced yes)
		(property "Reference" "L7"
			(at 316.23 196.85 0)
			(effects
				(font
					(size 1.27 1.27)
					(thickness 0.15)
				)
			)
		)
		(property "Value" "L_3u3_3.1A_Bourns-SRP3212A"
			(at 327.66 204.47 0)
			(effects
				(font
					(size 1.27 1.27)
					(thickness 0.15)
				)
				(justify left bottom)
				(hide yes)
			)
		)
		(property "Footprint" "antmicro-footprints:L_Bourns-SRP3212A"
			(at 327.66 209.55 0)
			(effects
				(font
					(size 1.27 1.27)
					(thickness 0.15)
				)
				(justify left bottom)
				(hide yes)
			)
		)
		(property "Datasheet" "https://www.mouser.com/datasheet/2/54/SRP3212A-3011944.pdf"
			(at 327.66 212.09 0)
			(effects
				(font
					(size 1.27 1.27)
					(thickness 0.15)
				)
				(justify left bottom)
				(hide yes)
			)
		)
		(property "Description" ""
			(at 313.69 201.93 0)
			(effects
				(font
					(size 1.27 1.27)
				)
				(hide yes)
			)
		)
		(property "Val" "3u3/3.1A"
			(at 316.23 199.39 0)
			(effects
				(font
					(size 1.27 1.27)
					(thickness 0.15)
				)
			)
		)
		(property "Manufacturer" "Bourns"
			(at 327.66 214.63 0)
			(effects
				(font
					(size 1.27 1.27)
					(thickness 0.15)
				)
				(justify left bottom)
				(hide yes)
			)
		)
		(property "MPN" "SRP3212-3R3M"
			(at 327.66 217.17 0)
			(effects
				(font
					(size 1.27 1.27)
					(thickness 0.15)
				)
				(justify left bottom)
				(hide yes)
			)
		)
		(property "ISat" "3.4 A"
			(at 327.66 218.44 0)
			(effects
				(font
					(size 1.27 1.27)
				)
				(justify left)
				(hide yes)
			)
		)
		(property "IMax" "3.1 A"
			(at 327.66 222.25 0)
			(effects
				(font
					(size 1.27 1.27)
					(thickness 0.15)
				)
				(justify left bottom)
				(hide yes)
			)
		)
		(property "Size" "3.2x2.5"
			(at 327.66 224.79 0)
			(effects
				(font
					(size 1.27 1.27)
					(thickness 0.15)
				)
				(justify left bottom)
				(hide yes)
			)
		)
		(property "Author" "Antmicro"
			(at 327.66 227.33 0)
			(effects
				(font
					(size 1.27 1.27)
					(thickness 0.15)
				)
				(justify left bottom)
				(hide yes)
			)
		)
		(property "License" "Apache-2.0"
			(at 327.66 229.87 0)
			(effects
				(font
					(size 1.27 1.27)
					(thickness 0.15)
				)
				(justify left bottom)
				(hide yes)
			)
		)
		(pin "1"
		)
		(pin "2"
		)
		(instances
			(project "gmsl-serializer"
				(path ""
					(reference "L7")
					(unit 1)
				)
			)
		)
	)
	(symbol
		(lib_id "antmicroFixedInductors:L_3u3_3.1A_Bourns-SRP3212A")
		(at 128.27 81.28 0)
		(unit 1)
		(exclude_from_sim no)
		(in_bom yes)
		(on_board yes)
		(dnp no)
		(fields_autoplaced yes)
		(property "Reference" "L1"
			(at 130.81 76.2 0)
			(effects
				(font
					(size 1.27 1.27)
					(thickness 0.15)
				)
			)
		)
		(property "Value" "L_3u3_3.1A_Bourns-SRP3212A"
			(at 142.24 83.82 0)
			(effects
				(font
					(size 1.27 1.27)
					(thickness 0.15)
				)
				(justify left bottom)
				(hide yes)
			)
		)
		(property "Footprint" "antmicro-footprints:L_Bourns-SRP3212A"
			(at 142.24 88.9 0)
			(effects
				(font
					(size 1.27 1.27)
					(thickness 0.15)
				)
				(justify left bottom)
				(hide yes)
			)
		)
		(property "Datasheet" "https://www.mouser.com/datasheet/2/54/SRP3212A-3011944.pdf"
			(at 142.24 91.44 0)
			(effects
				(font
					(size 1.27 1.27)
					(thickness 0.15)
				)
				(justify left bottom)
				(hide yes)
			)
		)
		(property "Description" ""
			(at 128.27 81.28 0)
			(effects
				(font
					(size 1.27 1.27)
				)
				(hide yes)
			)
		)
		(property "Val" "3u3/3.1A"
			(at 130.81 78.74 0)
			(effects
				(font
					(size 1.27 1.27)
					(thickness 0.15)
				)
			)
		)
		(property "Manufacturer" "Bourns"
			(at 142.24 93.98 0)
			(effects
				(font
					(size 1.27 1.27)
					(thickness 0.15)
				)
				(justify left bottom)
				(hide yes)
			)
		)
		(property "MPN" "SRP3212-3R3M"
			(at 142.24 96.52 0)
			(effects
				(font
					(size 1.27 1.27)
					(thickness 0.15)
				)
				(justify left bottom)
				(hide yes)
			)
		)
		(property "ISat" "3.4 A"
			(at 142.24 97.79 0)
			(effects
				(font
					(size 1.27 1.27)
				)
				(justify left)
				(hide yes)
			)
		)
		(property "IMax" "3.1 A"
			(at 142.24 101.6 0)
			(effects
				(font
					(size 1.27 1.27)
					(thickness 0.15)
				)
				(justify left bottom)
				(hide yes)
			)
		)
		(property "Size" "3.2x2.5"
			(at 142.24 104.14 0)
			(effects
				(font
					(size 1.27 1.27)
					(thickness 0.15)
				)
				(justify left bottom)
				(hide yes)
			)
		)
		(property "Author" "Antmicro"
			(at 142.24 106.68 0)
			(effects
				(font
					(size 1.27 1.27)
					(thickness 0.15)
				)
				(justify left bottom)
				(hide yes)
			)
		)
		(property "License" "Apache-2.0"
			(at 142.24 109.22 0)
			(effects
				(font
					(size 1.27 1.27)
					(thickness 0.15)
				)
				(justify left bottom)
				(hide yes)
			)
		)
		(pin "1"
		)
		(pin "2"
		)
		(instances
			(project "gmsl-serializer"
				(path ""
					(reference "L1")
					(unit 1)
				)
			)
		)
	)
	(symbol
		(lib_id "antmicroCapacitors0603:C_10u_25V_0603")
		(at 76.2 90.17 90)
		(unit 1)
		(exclude_from_sim no)
		(in_bom yes)
		(on_board yes)
		(dnp no)
		(property "Reference" "C1"
			(at 77.47 85.09 90)
			(effects
				(font
					(size 1.27 1.27)
					(thickness 0.15)
				)
				(justify right)
			)
		)
		(property "Value" "C_10u_25V_0603"
			(at 86.36 69.85 0)
			(effects
				(font
					(size 1.27 1.27)
					(thickness 0.15)
				)
				(justify left bottom)
				(hide yes)
			)
		)
		(property "Footprint" "antmicro-footprints:C_0603_1608Metric"
			(at 88.9 69.85 0)
			(effects
				(font
					(size 1.27 1.27)
					(thickness 0.15)
				)
				(justify left bottom)
				(hide yes)
			)
		)
		(property "Datasheet" "https://product.tdk.com/en/search/capacitor/ceramic/mlcc/info?part_no=C1608X5R1E106M080AC"
			(at 91.44 69.85 0)
			(effects
				(font
					(size 1.27 1.27)
					(thickness 0.15)
				)
				(justify left bottom)
				(hide yes)
			)
		)
		(property "Description" ""
			(at 76.2 90.17 0)
			(effects
				(font
					(size 1.27 1.27)
				)
				(hide yes)
			)
		)
		(property "MPN" "C1608X5R1E106M080AC"
			(at 93.98 69.85 0)
			(effects
				(font
					(size 1.27 1.27)
					(thickness 0.15)
				)
				(justify left bottom)
				(hide yes)
			)
		)
		(property "Manufacturer" "TDK"
			(at 96.52 69.85 0)
			(effects
				(font
					(size 1.27 1.27)
					(thickness 0.15)
				)
				(justify left bottom)
				(hide yes)
			)
		)
		(property "License" "Apache-2.0"
			(at 99.06 69.85 0)
			(effects
				(font
					(size 1.27 1.27)
					(thickness 0.15)
				)
				(justify left bottom)
				(hide yes)
			)
		)
		(property "Author" "Antmicro"
			(at 101.6 69.85 0)
			(effects
				(font
					(size 1.27 1.27)
					(thickness 0.15)
				)
				(justify left bottom)
				(hide yes)
			)
		)
		(property "Val" "10u"
			(at 77.47 89.535 90)
			(effects
				(font
					(size 1.27 1.27)
					(thickness 0.15)
				)
				(justify right)
			)
		)
		(property "Voltage" "25V"
			(at 104.14 69.85 0)
			(effects
				(font
					(size 1.27 1.27)
				)
				(justify left bottom)
				(hide yes)
			)
		)
		(property "Dielectric" ""
			(at 106.68 69.85 0)
			(effects
				(font
					(size 1.27 1.27)
				)
				(justify left bottom)
				(hide yes)
			)
		)
		(pin "1"
		)
		(pin "2"
		)
		(instances
			(project "gmsl-serializer"
				(path ""
					(reference "C1")
					(unit 1)
				)
			)
		)
	)
	(symbol
		(lib_id "antmicropower:GND")
		(at 54.61 95.25 0)
		(unit 1)
		(exclude_from_sim no)
		(in_bom yes)
		(on_board yes)
		(dnp no)
		(property "Reference" "#PWR019"
			(at 63.5 97.79 0)
			(effects
				(font
					(size 1.27 1.27)
					(thickness 0.15)
				)
				(justify left bottom)
				(hide yes)
			)
		)
		(property "Value" "GND"
			(at 54.61 99.06 0)
			(effects
				(font
					(size 1.27 1.27)
					(thickness 0.15)
				)
			)
		)
		(property "Footprint" ""
			(at 63.5 102.87 0)
			(effects
				(font
					(size 1.27 1.27)
					(thickness 0.15)
				)
				(justify left bottom)
				(hide yes)
			)
		)
		(property "Datasheet" ""
			(at 63.5 107.95 0)
			(effects
				(font
					(size 1.27 1.27)
					(thickness 0.15)
				)
				(justify left bottom)
				(hide yes)
			)
		)
		(property "Description" ""
			(at 54.61 95.25 0)
			(effects
				(font
					(size 1.27 1.27)
				)
				(hide yes)
			)
		)
		(property "Author" "Antmicro"
			(at 63.5 102.87 0)
			(effects
				(font
					(size 1.27 1.27)
					(thickness 0.15)
				)
				(justify left bottom)
				(hide yes)
			)
		)
		(property "License" "Apache-2.0"
			(at 63.5 105.41 0)
			(effects
				(font
					(size 1.27 1.27)
					(thickness 0.15)
				)
				(justify left bottom)
				(hide yes)
			)
		)
		(pin "1"
		)
		(instances
			(project "gmsl-serializer"
				(path ""
					(reference "#PWR019")
					(unit 1)
				)
			)
		)
	)
	(symbol
		(lib_id "antmicropower:GND")
		(at 118.11 223.52 0)
		(unit 1)
		(exclude_from_sim no)
		(in_bom yes)
		(on_board yes)
		(dnp no)
		(property "Reference" "#PWR0113"
			(at 127 226.06 0)
			(effects
				(font
					(size 1.27 1.27)
					(thickness 0.15)
				)
				(justify left bottom)
				(hide yes)
			)
		)
		(property "Value" "GND"
			(at 118.11 227.33 0)
			(effects
				(font
					(size 1.27 1.27)
					(thickness 0.15)
				)
			)
		)
		(property "Footprint" ""
			(at 127 231.14 0)
			(effects
				(font
					(size 1.27 1.27)
					(thickness 0.15)
				)
				(justify left bottom)
				(hide yes)
			)
		)
		(property "Datasheet" ""
			(at 127 236.22 0)
			(effects
				(font
					(size 1.27 1.27)
					(thickness 0.15)
				)
				(justify left bottom)
				(hide yes)
			)
		)
		(property "Description" ""
			(at 118.11 223.52 0)
			(effects
				(font
					(size 1.27 1.27)
				)
				(hide yes)
			)
		)
		(property "Author" "Antmicro"
			(at 127 231.14 0)
			(effects
				(font
					(size 1.27 1.27)
					(thickness 0.15)
				)
				(justify left bottom)
				(hide yes)
			)
		)
		(property "License" "Apache-2.0"
			(at 127 233.68 0)
			(effects
				(font
					(size 1.27 1.27)
					(thickness 0.15)
				)
				(justify left bottom)
				(hide yes)
			)
		)
		(pin "1"
		)
		(instances
			(project "gmsl-serializer"
				(path ""
					(reference "#PWR0113")
					(unit 1)
				)
			)
		)
	)
	(symbol
		(lib_id "antmicroCapacitors0402:C_22u_0402")
		(at 135.89 222.25 90)
		(unit 1)
		(exclude_from_sim no)
		(in_bom yes)
		(on_board yes)
		(dnp no)
		(property "Reference" "C8"
			(at 138.43 218.44 90)
			(effects
				(font
					(size 1.27 1.27)
					(thickness 0.15)
				)
				(justify right)
			)
		)
		(property "Value" "C_22u_0402"
			(at 146.05 201.93 0)
			(effects
				(font
					(size 1.27 1.27)
					(thickness 0.15)
				)
				(justify left bottom)
				(hide yes)
			)
		)
		(property "Footprint" "antmicro-footprints:C_0402_1005Metric"
			(at 148.59 201.93 0)
			(effects
				(font
					(size 1.27 1.27)
					(thickness 0.15)
				)
				(justify left bottom)
				(hide yes)
			)
		)
		(property "Datasheet" "https://www.murata.com/products/productdetail?partno=GRM158R60J226ME01%23"
			(at 151.13 201.93 0)
			(effects
				(font
					(size 1.27 1.27)
					(thickness 0.15)
				)
				(justify left bottom)
				(hide yes)
			)
		)
		(property "Description" ""
			(at 135.89 222.25 0)
			(effects
				(font
					(size 1.27 1.27)
				)
				(hide yes)
			)
		)
		(property "MPN" "GRM158R60J226ME01D"
			(at 153.67 201.93 0)
			(effects
				(font
					(size 1.27 1.27)
					(thickness 0.15)
				)
				(justify left bottom)
				(hide yes)
			)
		)
		(property "Manufacturer" "Murata"
			(at 156.21 201.93 0)
			(effects
				(font
					(size 1.27 1.27)
					(thickness 0.15)
				)
				(justify left bottom)
				(hide yes)
			)
		)
		(property "License" "Apache-2.0"
			(at 158.75 201.93 0)
			(effects
				(font
					(size 1.27 1.27)
					(thickness 0.15)
				)
				(justify left bottom)
				(hide yes)
			)
		)
		(property "Author" "Antmicro"
			(at 161.29 201.93 0)
			(effects
				(font
					(size 1.27 1.27)
					(thickness 0.15)
				)
				(justify left bottom)
				(hide yes)
			)
		)
		(property "Val" "22u"
			(at 138.43 220.98 90)
			(effects
				(font
					(size 1.27 1.27)
					(thickness 0.15)
				)
				(justify right)
			)
		)
		(property "Voltage" ""
			(at 163.83 201.93 0)
			(effects
				(font
					(size 1.27 1.27)
				)
				(justify left bottom)
				(hide yes)
			)
		)
		(property "Dielectric" ""
			(at 166.37 201.93 0)
			(effects
				(font
					(size 1.27 1.27)
				)
				(justify left bottom)
				(hide yes)
			)
		)
		(pin "1"
		)
		(pin "2"
		)
		(instances
			(project "gmsl-serializer"
				(path ""
					(reference "C8")
					(unit 1)
				)
			)
		)
	)
	(symbol
		(lib_id "antmicropower:+12V")
		(at 273.05 193.04 0)
		(unit 1)
		(exclude_from_sim no)
		(in_bom yes)
		(on_board yes)
		(dnp no)
		(fields_autoplaced yes)
		(property "Reference" "#PWR023"
			(at 273.05 196.85 0)
			(effects
				(font
					(size 1.27 1.27)
				)
				(hide yes)
			)
		)
		(property "Value" "+12V"
			(at 273.05 187.96 0)
			(effects
				(font
					(size 1.27 1.27)
				)
			)
		)
		(property "Footprint" ""
			(at 273.05 193.04 0)
			(effects
				(font
					(size 1.27 1.27)
				)
				(hide yes)
			)
		)
		(property "Datasheet" ""
			(at 273.05 193.04 0)
			(effects
				(font
					(size 1.27 1.27)
				)
				(hide yes)
			)
		)
		(property "Description" ""
			(at 273.05 193.04 0)
			(effects
				(font
					(size 1.27 1.27)
				)
				(hide yes)
			)
		)
		(pin "1"
		)
		(instances
			(project "gmsl-serializer"
				(path ""
					(reference "#PWR023")
					(unit 1)
				)
			)
		)
	)
)
